FILE_TYPE = MACRO_DRAWING;
SET COLOR_WIRE YELLOW;
SET COLOR_PROP MONO;
SET COLOR_DOT WHITE;
SET COLOR_ARC YELLOW;
SET COLOR_BODY GREEN;
SET COLOR_NOTE MONO;
SET PROP_DISPLAY VALUE;
SET PAGE_NUMBER P205;
FORCEADD OFFPAGE..2
(-1625 4675);
FORCEPROP 2 LAST $XR0 201 
J 0
(-1436 4675);
DISPLAY 0.638298 (-1436 4675);
PAINT MONO (-1436 4675);
FORCEPROP 2 LAST BOM_COST PROC_VRD_VCCIN_CPU0
J 0
(-1425 4725);
DISPLAY 1.446809 (-1425 4725);
PAINT MONO (-1425 4725);
DISPLAY INVISIBLE (-1425 4725);
FORCEPROP 2 LAST PATH I1
J 0
(-1445 4750);
DISPLAY 1.021277 (-1445 4750);
PAINT ORANGE (-1445 4750);
DISPLAY INVISIBLE (-1445 4750);
FORCEPROP 1 LAST OFFPAGE TRUE
J 0
(-1300 4550);
DISPLAY 1.723404 (-1300 4550);
PAINT GREEN (-1300 4550);
DISPLAY INVISIBLE (-1300 4550);
FORCEPROP 2 LAST ROOM PVSA_CPU0_PWR_VR
J 0
(-2025 4750);
DISPLAY 1.936170 (-2025 4750);
PAINT ORANGE (-2025 4750);
DISPLAY INVISIBLE (-2025 4750);
FORCEPROP 2 LAST CDS_LIB mstr_standard
J 0
(-1625 4675);
PAINT ORANGE (-1625 4675);
DISPLAY INVISIBLE (-1625 4675);
FORCEPROP 1 LAST COMMENT_BODY TRUE
J 0
(-1670 4580);
DISPLAY 1.723404 (-1670 4580);
PAINT GREEN (-1670 4580);
DISPLAY INVISIBLE (-1670 4580);
FORCEADD PVSA_CPU0..1
(-2000 1675);
FORCEPROP 3 LASTPIN (-2000 1625) SIG_NAME PVSA_CPU0\g
J 0
(-1990 1635);
DISPLAY 0.659574 (-1990 1635);
PAINT MONO (-1990 1635);
DISPLAY INVISIBLE (-1990 1635);
FORCEPROP 1 LAST VOLTAGE 1.1V
J 0
(-2045 1632);
DISPLAY 0.340426 (-2045 1632);
PAINT SKYBLUE (-2045 1632);
DISPLAY INVISIBLE (-2045 1632);
FORCEPROP 2 LAST CDS_LIB mstr_symbols
J 0
(-2000 1675);
PAINT ORANGE (-2000 1675);
DISPLAY INVISIBLE (-2000 1675);
FORCEPROP 1 LAST BODY_TYPE PLUMBING
J 0
(-2045 1632);
DISPLAY 0.340426 (-2045 1632);
PAINT GREEN (-2045 1632);
DISPLAY INVISIBLE (-2045 1632);
FORCEPROP 1 LAST PATH I11
J 0
(-1950 1700);
DISPLAY 0.872340 (-1950 1700);
PAINT AQUA (-1950 1700);
DISPLAY INVISIBLE (-1950 1700);
FORCEPROP 1 LAST HDL_POWER PVSA_CPU0
J 1
(-2000 1725);
DISPLAY 0.872340 (-2000 1725);
PAINT GREEN (-2000 1725);
DISPLAY INVISIBLE (-2000 1725);
FORCEADD CAPP..1
(-2000 1300);
FORCEPROP 1 LAST PART_NUMBER 699013-049
J 0
(-1950 1100);
DISPLAY 0.617021 (-1950 1100);
PAINT BLUE (-1950 1100);
FORCEPROP 1 LAST LOCATION C6N1
J 0
(-1950 1400);
DISPLAY 0.617021 (-1950 1400);
PAINT AQUA (-1950 1400);
FORCEPROP 1 LAST VALUE 470UF
J 0
(-1950 1350);
DISPLAY 0.617021 (-1950 1350);
PAINT SKYBLUE (-1950 1350);
FORCEPROP 1 LAST TOLERANCE 20%
J 0
(-1950 1300);
DISPLAY 0.617021 (-1950 1300);
PAINT SKYBLUE (-1950 1300);
FORCEPROP 1 LASTPIN (-2000 1400) $PN 1
J 0
(-1990 1385);
DISPLAY 0.617021 (-1990 1385);
PAINT ORANGE (-1990 1385);
FORCEPROP 1 LAST PACK_TYPE 3018
J 0
(-1950 1150);
DISPLAY 0.617021 (-1950 1150);
PAINT SKYBLUE (-1950 1150);
FORCEPROP 1 LAST VOLTAGE 2.5V
J 0
(-1950 1250);
DISPLAY 0.617021 (-1950 1250);
PAINT SKYBLUE (-1950 1250);
FORCEPROP 1 LAST MATERIAL ALUM
J 0
(-1950 1200);
DISPLAY 0.617021 (-1950 1200);
PAINT SKYBLUE (-1950 1200);
FORCEPROP 1 LASTPIN (-2000 1200) $PN 2
J 0
(-1990 1185);
DISPLAY 0.617021 (-1990 1185);
PAINT ORANGE (-1990 1185);
FORCEPROP 2 LAST SEC_TYPE 3018
J 0
(-1945 1520);
DISPLAY 1.021277 (-1945 1520);
PAINT ORANGE (-1945 1520);
DISPLAY INVISIBLE (-1945 1520);
FORCEPROP 2 LAST SEC 1
J 0
(-1950 1500);
PAINT MONO (-1950 1500);
DISPLAY INVISIBLE (-1950 1500);
FORCEPROP 2 LAST BOM_COST PROC_VRD_VCCIN_CPU0
J 0
(-1950 1450);
PAINT MONO (-1950 1450);
DISPLAY INVISIBLE (-1950 1450);
FORCEPROP 1 LAST PATH I12
J 0
(-1950 1450);
DISPLAY 0.978723 (-1950 1450);
PAINT ORANGE (-1950 1450);
DISPLAY INVISIBLE (-1950 1450);
FORCEPROP 2 LAST ROOM PVSA_CPU0_DECAP_VR
J 0
(-1950 1425);
PAINT MONO (-1950 1425);
DISPLAY INVISIBLE (-1950 1425);
FORCEPROP 2 LAST CDS_LOCATION C6N1
J 0
(-1950 1400);
DISPLAY 0.617021 (-1950 1400);
PAINT AQUA (-1950 1400);
DISPLAY INVISIBLE (-1950 1400);
FORCEPROP 2 LAST CDS_LIB mstr_discrete
J 0
(-2000 1300);
PAINT ORANGE (-2000 1300);
DISPLAY INVISIBLE (-2000 1300);
FORCEADD GND..1
(-2000 900);
FORCEPROP 3 LASTPIN (-2000 950) SIG_NAME GND\g
J 0
(-1990 960);
DISPLAY 0.659574 (-1990 960);
PAINT MONO (-1990 960);
DISPLAY INVISIBLE (-1990 960);
FORCEPROP 1 LAST HDL_POWER GND
J 0
(-2000 1050);
DISPLAY 1.723404 (-2000 1050);
PAINT GREEN (-2000 1050);
DISPLAY INVISIBLE (-2000 1050);
FORCEPROP 2 LAST CDS_LIB mstr_symbols
J 0
(-2000 900);
PAINT ORANGE (-2000 900);
DISPLAY INVISIBLE (-2000 900);
FORCEPROP 1 LAST SIZE 1B
J 0
(-1925 850);
DISPLAY 1.723404 (-1925 850);
PAINT GREEN (-1925 850);
DISPLAY INVISIBLE (-1925 850);
FORCEPROP 1 LAST BODY_TYPE PLUMBING
J 0
(-2045 857);
DISPLAY 0.340426 (-2045 857);
PAINT GREEN (-2045 857);
DISPLAY INVISIBLE (-2045 857);
FORCEPROP 1 LAST PATH I13
J 0
(-1925 900);
DISPLAY 0.872340 (-1925 900);
PAINT AQUA (-1925 900);
DISPLAY INVISIBLE (-1925 900);
FORCEPROP 1 LAST VOLTAGE 0
J 0
(-2000 900);
PAINT SKYBLUE (-2000 900);
DISPLAY INVISIBLE (-2000 900);
FORCEPROP 2 LAST BOM_COST PROC_VRD_VCCIN_CPU0
J 0
(-2375 975);
DISPLAY 1.446809 (-2375 975);
PAINT MONO (-2375 975);
DISPLAY INVISIBLE (-2375 975);
FORCEPROP 2 LAST ROOM PVSA_CPU0_DECAP_VR
J 0
(-2550 975);
DISPLAY 1.936170 (-2550 975);
PAINT ORANGE (-2550 975);
DISPLAY INVISIBLE (-2550 975);
FORCEADD CAPP..1
R 2
(-2250 1300);
FORCEPROP 1 LAST PART_NUMBER 699013-049
J 2
(-2300 1100);
DISPLAY 0.617021 (-2300 1100);
PAINT BLUE (-2300 1100);
FORCEPROP 1 LAST VALUE 470UF
J 2
(-2300 1350);
DISPLAY 0.617021 (-2300 1350);
PAINT SKYBLUE (-2300 1350);
FORCEPROP 1 LASTPIN (-2250 1400) $PN 1
J 2
(-2260 1385);
DISPLAY 0.617021 (-2260 1385);
PAINT GREEN (-2260 1385);
FORCEPROP 1 LASTPIN (-2250 1200) $PN 2
J 2
(-2260 1185);
DISPLAY 0.617021 (-2260 1185);
PAINT GREEN (-2260 1185);
FORCEPROP 1 LAST LOCATION C6N4
J 2
(-2300 1400);
DISPLAY 0.617021 (-2300 1400);
PAINT AQUA (-2300 1400);
FORCEPROP 1 LAST TOLERANCE 20%
J 2
(-2300 1300);
DISPLAY 0.617021 (-2300 1300);
PAINT SKYBLUE (-2300 1300);
FORCEPROP 1 LAST PACK_TYPE 3018
J 2
(-2300 1150);
DISPLAY 0.617021 (-2300 1150);
PAINT SKYBLUE (-2300 1150);
FORCEPROP 1 LAST VOLTAGE 2.5V
J 2
(-2300 1250);
DISPLAY 0.617021 (-2300 1250);
PAINT SKYBLUE (-2300 1250);
FORCEPROP 1 LAST MATERIAL ALUM
J 2
(-2300 1200);
DISPLAY 0.617021 (-2300 1200);
PAINT SKYBLUE (-2300 1200);
FORCEPROP 2 LAST SEC_TYPE 3018
J 0
(-2290 1515);
DISPLAY 1.021277 (-2290 1515);
PAINT ORANGE (-2290 1515);
DISPLAY INVISIBLE (-2290 1515);
FORCEPROP 2 LAST SEC 1
J 0
(-2290 1515);
DISPLAY 0.680851 (-2290 1515);
PAINT MONO (-2290 1515);
DISPLAY INVISIBLE (-2290 1515);
FORCEPROP 2 LAST BOM_COST PROC_VRD_VCCIN_CPU0
J 2
(-2300 1450);
PAINT MONO (-2300 1450);
DISPLAY INVISIBLE (-2300 1450);
FORCEPROP 1 LAST PATH I14
J 2
(-2300 1450);
DISPLAY 0.978723 (-2300 1450);
PAINT ORANGE (-2300 1450);
DISPLAY INVISIBLE (-2300 1450);
FORCEPROP 2 LAST ROOM PVSA_CPU0_DECAP_VR
J 2
(-2300 1425);
PAINT MONO (-2300 1425);
DISPLAY INVISIBLE (-2300 1425);
FORCEPROP 2 LAST CDS_LOCATION C6N4
J 2
(-2300 1400);
DISPLAY 0.617021 (-2300 1400);
PAINT AQUA (-2300 1400);
DISPLAY INVISIBLE (-2300 1400);
FORCEPROP 2 LAST CDS_LIB mstr_discrete
J 2
(-2250 1300);
PAINT ORANGE (-2250 1300);
DISPLAY INVISIBLE (-2250 1300);
FORCEADD GND..1
(-2825 3075);
FORCEPROP 3 LASTPIN (-2825 3125) SIG_NAME GND\g
J 0
(-2815 3135);
DISPLAY 0.659574 (-2815 3135);
PAINT MONO (-2815 3135);
DISPLAY INVISIBLE (-2815 3135);
FORCEPROP 1 LAST PATH I15
J 0
(-2750 3075);
DISPLAY 0.872340 (-2750 3075);
PAINT AQUA (-2750 3075);
DISPLAY INVISIBLE (-2750 3075);
FORCEPROP 1 LAST HDL_POWER GND
J 0
(-2825 3225);
DISPLAY 1.723404 (-2825 3225);
PAINT GREEN (-2825 3225);
DISPLAY INVISIBLE (-2825 3225);
FORCEPROP 2 LAST CDS_LIB mstr_symbols
J 0
(-2825 3075);
PAINT ORANGE (-2825 3075);
DISPLAY INVISIBLE (-2825 3075);
FORCEPROP 1 LAST VOLTAGE 0
J 0
(-2825 3075);
PAINT SKYBLUE (-2825 3075);
DISPLAY INVISIBLE (-2825 3075);
FORCEPROP 1 LAST SIZE 1B
J 0
(-2750 3025);
DISPLAY 1.723404 (-2750 3025);
PAINT GREEN (-2750 3025);
DISPLAY INVISIBLE (-2750 3025);
FORCEPROP 1 LAST BODY_TYPE PLUMBING
J 0
(-2870 3032);
DISPLAY 0.340426 (-2870 3032);
PAINT GREEN (-2870 3032);
DISPLAY INVISIBLE (-2870 3032);
FORCEPROP 2 LAST BOM_COST PROC_VRD_VCCIN_CPU0
J 0
(-3200 3150);
DISPLAY 1.446809 (-3200 3150);
PAINT MONO (-3200 3150);
DISPLAY INVISIBLE (-3200 3150);
FORCEPROP 2 LAST ROOM PVSA_CPU0_PWR_VR
J 0
(-3375 3150);
DISPLAY 1.936170 (-3375 3150);
PAINT ORANGE (-3375 3150);
DISPLAY INVISIBLE (-3375 3150);
FORCEADD CAP..1
(-5775 4000);
FORCEPROP 1 LASTPIN (-5775 3900) $PN 2
J 0
(-5765 3880);
DISPLAY 0.617021 (-5765 3880);
PAINT ORANGE (-5765 3880);
FORCEPROP 1 LAST PACK_TYPE 0402
J 0
(-5725 3800);
DISPLAY 0.617021 (-5725 3800);
PAINT SKYBLUE (-5725 3800);
FORCEPROP 1 LAST VOLTAGE 16V
J 0
(-5725 4000);
DISPLAY 0.617021 (-5725 4000);
PAINT SKYBLUE (-5725 4000);
FORCEPROP 1 LAST MATERIAL X7R
J 0
(-5725 3900);
DISPLAY 0.617021 (-5725 3900);
PAINT SKYBLUE (-5725 3900);
FORCEPROP 1 LAST LOCATION C4C5
J 0
(-5725 4100);
DISPLAY 0.617021 (-5725 4100);
PAINT AQUA (-5725 4100);
FORCEPROP 1 LASTPIN (-5775 4100) $PN 1
J 0
(-5765 4080);
DISPLAY 0.617021 (-5765 4080);
PAINT ORANGE (-5765 4080);
FORCEPROP 1 LAST PART_NUMBER A36096-155
J 0
(-5725 3850);
DISPLAY 0.617021 (-5725 3850);
PAINT BLUE (-5725 3850);
FORCEPROP 1 LAST VALUE 0.22UF
J 0
(-5725 4050);
DISPLAY 0.617021 (-5725 4050);
PAINT SKYBLUE (-5725 4050);
FORCEPROP 1 LAST TOLERANCE 10%
J 0
(-5725 3950);
DISPLAY 0.617021 (-5725 3950);
PAINT SKYBLUE (-5725 3950);
FORCEPROP 2 LAST ROOM PVSA_CPU0_PWR_VR
J 0
(-5725 4150);
DISPLAY 1.361702 (-5725 4150);
PAINT ORANGE (-5725 4150);
DISPLAY INVISIBLE (-5725 4150);
FORCEPROP 1 LAST PATH I16
J 0
(-5725 4150);
DISPLAY 0.978723 (-5725 4150);
PAINT WHITE (-5725 4150);
DISPLAY INVISIBLE (-5725 4150);
FORCEPROP 2 LAST CDS_LOCATION C4C5
J 0
(-5725 4100);
DISPLAY 0.617021 (-5725 4100);
PAINT AQUA (-5725 4100);
DISPLAY INVISIBLE (-5725 4100);
FORCEPROP 2 LAST SEC 1
J 0
(-5725 4200);
DISPLAY 0.680851 (-5725 4200);
PAINT MONO (-5725 4200);
DISPLAY INVISIBLE (-5725 4200);
FORCEPROP 2 LAST SEC_TYPE 0402
J 0
(-5725 4200);
DISPLAY 1.021277 (-5725 4200);
PAINT ORANGE (-5725 4200);
DISPLAY INVISIBLE (-5725 4200);
FORCEPROP 2 LAST CDS_LIB mstr_discrete
J 0
(-5775 4000);
PAINT ORANGE (-5775 4000);
DISPLAY INVISIBLE (-5775 4000);
FORCEADD CAP_A..1
R 2
(-5875 4000);
FORCEPROP 1 LAST VALUE 1.0UF
J 2
(-5925 4050);
DISPLAY 0.617021 (-5925 4050);
PAINT SKYBLUE (-5925 4050);
FORCEPROP 1 LAST TOLERANCE 10%
J 2
(-5925 3950);
DISPLAY 0.617021 (-5925 3950);
PAINT SKYBLUE (-5925 3950);
FORCEPROP 1 LAST LOCATION C4C4
J 2
(-5925 4100);
DISPLAY 0.617021 (-5925 4100);
PAINT AQUA (-5925 4100);
FORCEPROP 1 LAST MATERIAL X6S
J 2
(-5925 3900);
DISPLAY 0.617021 (-5925 3900);
PAINT SKYBLUE (-5925 3900);
FORCEPROP 1 LASTPIN (-5875 4100) $PN 1
J 2
(-5885 4080);
DISPLAY 0.617021 (-5885 4080);
PAINT ORANGE (-5885 4080);
FORCEPROP 1 LASTPIN (-5875 3900) $PN 2
J 2
(-5885 3880);
DISPLAY 0.617021 (-5885 3880);
PAINT ORANGE (-5885 3880);
FORCEPROP 1 LAST PACK_TYPE 0402V
J 2
(-5925 3800);
DISPLAY 0.617021 (-5925 3800);
PAINT SKYBLUE (-5925 3800);
FORCEPROP 1 LAST VOLTAGE 6.3V
J 2
(-5925 4000);
DISPLAY 0.617021 (-5925 4000);
PAINT SKYBLUE (-5925 4000);
FORCEPROP 1 LAST PART_NUMBER D97712-004
J 2
(-5925 3850);
DISPLAY 0.617021 (-5925 3850);
PAINT BLUE (-5925 3850);
FORCEPROP 2 LAST CDS_LOCATION C4C4
J 2
(-5925 4100);
DISPLAY 0.617021 (-5925 4100);
PAINT AQUA (-5925 4100);
DISPLAY INVISIBLE (-5925 4100);
FORCEPROP 2 LAST CDS_SEC 1
J 0
(-5925 4150);
PAINT ORANGE (-5925 4150);
DISPLAY INVISIBLE (-5925 4150);
FORCEPROP 2 LAST SEC_TYPE 0402V
J 0
(-5925 4200);
DISPLAY 1.021277 (-5925 4200);
PAINT ORANGE (-5925 4200);
DISPLAY INVISIBLE (-5925 4200);
FORCEPROP 2 LAST SEC 1
J 0
(-5925 4200);
DISPLAY 0.680851 (-5925 4200);
PAINT MONO (-5925 4200);
DISPLAY INVISIBLE (-5925 4200);
FORCEPROP 1 LAST PATH I18
J 2
(-5925 4150);
DISPLAY 0.978723 (-5925 4150);
PAINT WHITE (-5925 4150);
DISPLAY INVISIBLE (-5925 4150);
FORCEPROP 2 LAST ROOM PVSA_CPU0_PWR_VR
J 0
(-5925 4150);
DISPLAY 1.361702 (-5925 4150);
PAINT ORANGE (-5925 4150);
DISPLAY INVISIBLE (-5925 4150);
FORCEPROP 2 LAST CDS_LIB dev_discrete
J 0
(-5875 4000);
PAINT ORANGE (-5875 4000);
DISPLAY INVISIBLE (-5875 4000);
FORCEADD RES..1
(-6075 4525);
FORCEPROP 1 LAST MATERIAL CHIP
J 0
(-6000 4350);
DISPLAY 0.617021 (-6000 4350);
PAINT SKYBLUE (-6000 4350);
FORCEPROP 1 LASTPIN (-5975 4525) $PN 2
J 0
(-6013 4537);
DISPLAY 0.617021 (-6013 4537);
PAINT ORANGE (-6013 4537);
FORCEPROP 1 LAST LOCATION R6N3
J 0
(-6125 4575);
DISPLAY 0.617021 (-6125 4575);
PAINT AQUA (-6125 4575);
FORCEPROP 1 LAST PACK_TYPE 0402
J 0
(-6025 4400);
DISPLAY 0.617021 (-6025 4400);
PAINT SKYBLUE (-6025 4400);
FORCEPROP 1 LAST TOLERANCE 1%
J 0
(-6125 4400);
DISPLAY 0.617021 (-6125 4400);
PAINT SKYBLUE (-6125 4400);
FORCEPROP 1 LAST PART_NUMBER G21796-090
J 0
(-6200 4450);
DISPLAY 0.617021 (-6200 4450);
PAINT BLUE (-6200 4450);
FORCEPROP 1 LAST WATTAGE 1/16W
J 2
(-6050 4350);
DISPLAY 0.617021 (-6050 4350);
PAINT SKYBLUE (-6050 4350);
FORCEPROP 1 LASTPIN (-6175 4525) $PN 1
J 0
(-6163 4537);
DISPLAY 0.617021 (-6163 4537);
PAINT ORANGE (-6163 4537);
FORCEPROP 1 LAST VALUE 1.0
J 2
(-6175 4400);
DISPLAY 0.617021 (-6175 4400);
PAINT SKYBLUE (-6175 4400);
FORCEPROP 2 LAST SEC_TYPE 0402
J 0
(-6125 4725);
DISPLAY 1.021277 (-6125 4725);
PAINT ORANGE (-6125 4725);
DISPLAY INVISIBLE (-6125 4725);
FORCEPROP 2 LAST SEC 1
J 0
(-6125 4725);
DISPLAY 0.680851 (-6125 4725);
PAINT MONO (-6125 4725);
DISPLAY INVISIBLE (-6125 4725);
FORCEPROP 1 LAST PATH I19
J 0
(-6125 4675);
DISPLAY 0.978723 (-6125 4675);
PAINT WHITE (-6125 4675);
DISPLAY INVISIBLE (-6125 4675);
FORCEPROP 2 LAST ROOM PVSA_CPU0_PWR_VR
J 0
(-6125 4625);
DISPLAY 1.361702 (-6125 4625);
PAINT ORANGE (-6125 4625);
DISPLAY INVISIBLE (-6125 4625);
FORCEPROP 2 LAST CDS_LIB mstr_discrete
J 0
(-6075 4525);
PAINT ORANGE (-6075 4525);
DISPLAY INVISIBLE (-6075 4525);
FORCEPROP 2 LAST CDS_LOCATION R6N3
J 0
(-6125 4575);
DISPLAY 0.617021 (-6125 4575);
PAINT AQUA (-6125 4575);
DISPLAY INVISIBLE (-6125 4575);
FORCEADD OFFPAGE..2
(-1700 4275);
FORCEPROP 2 LAST $XR0 201 
J 0
(-1511 4275);
DISPLAY 0.638298 (-1511 4275);
PAINT MONO (-1511 4275);
FORCEPROP 2 LAST PATH I2
J 0
(-1520 4350);
DISPLAY 1.021277 (-1520 4350);
PAINT ORANGE (-1520 4350);
DISPLAY INVISIBLE (-1520 4350);
FORCEPROP 1 LAST OFFPAGE TRUE
J 0
(-1375 4150);
DISPLAY 1.723404 (-1375 4150);
PAINT GREEN (-1375 4150);
DISPLAY INVISIBLE (-1375 4150);
FORCEPROP 2 LAST BOM_COST PROC_VRD_VCCIN_CPU0
J 0
(-1500 4325);
DISPLAY 1.446809 (-1500 4325);
PAINT MONO (-1500 4325);
DISPLAY INVISIBLE (-1500 4325);
FORCEPROP 2 LAST CDS_LIB mstr_standard
J 0
(-1700 4275);
PAINT ORANGE (-1700 4275);
DISPLAY INVISIBLE (-1700 4275);
FORCEPROP 1 LAST COMMENT_BODY TRUE
J 0
(-1745 4180);
DISPLAY 1.723404 (-1745 4180);
PAINT GREEN (-1745 4180);
DISPLAY INVISIBLE (-1745 4180);
FORCEPROP 2 LAST ROOM PVSA_CPU0_PWR_VR
J 0
(-2100 4350);
DISPLAY 1.936170 (-2100 4350);
PAINT ORANGE (-2100 4350);
DISPLAY INVISIBLE (-2100 4350);
FORCEADD CAP..1
(-6350 3950);
FORCEPROP 1 LAST LOCATION C4C6
J 0
(-6300 4050);
DISPLAY 0.617021 (-6300 4050);
PAINT AQUA (-6300 4050);
FORCEPROP 1 LAST VALUE 1.0UF
J 0
(-6300 4000);
DISPLAY 0.617021 (-6300 4000);
PAINT SKYBLUE (-6300 4000);
FORCEPROP 1 LAST PART_NUMBER D97712-011
J 0
(-6300 3800);
DISPLAY 0.617021 (-6300 3800);
PAINT BLUE (-6300 3800);
FORCEPROP 1 LAST TOLERANCE 10%
J 0
(-6300 3900);
DISPLAY 0.617021 (-6300 3900);
PAINT SKYBLUE (-6300 3900);
FORCEPROP 1 LAST VOLTAGE 16V
J 0
(-6300 3950);
DISPLAY 0.617021 (-6300 3950);
PAINT SKYBLUE (-6300 3950);
FORCEPROP 1 LAST MATERIAL X6S
J 0
(-6300 3850);
DISPLAY 0.617021 (-6300 3850);
PAINT SKYBLUE (-6300 3850);
FORCEPROP 1 LASTPIN (-6350 4050) $PN 1
J 0
(-6340 4030);
DISPLAY 0.617021 (-6340 4030);
PAINT ORANGE (-6340 4030);
FORCEPROP 1 LASTPIN (-6350 3850) $PN 2
J 0
(-6340 3830);
DISPLAY 0.617021 (-6340 3830);
PAINT ORANGE (-6340 3830);
FORCEPROP 1 LAST PACK_TYPE 0402
J 0
(-6300 3750);
DISPLAY 0.617021 (-6300 3750);
PAINT SKYBLUE (-6300 3750);
FORCEPROP 2 LAST ROOM PVSA_CPU0_PWR_VR
J 0
(-6300 4100);
DISPLAY 1.361702 (-6300 4100);
PAINT ORANGE (-6300 4100);
DISPLAY INVISIBLE (-6300 4100);
FORCEPROP 1 LAST PATH I20
J 0
(-6300 4100);
DISPLAY 0.978723 (-6300 4100);
PAINT WHITE (-6300 4100);
DISPLAY INVISIBLE (-6300 4100);
FORCEPROP 2 LAST SEC 1
J 0
(-6300 4150);
DISPLAY 0.680851 (-6300 4150);
PAINT MONO (-6300 4150);
DISPLAY INVISIBLE (-6300 4150);
FORCEPROP 2 LAST SEC_TYPE 0402
J 0
(-6300 4150);
DISPLAY 1.021277 (-6300 4150);
PAINT ORANGE (-6300 4150);
DISPLAY INVISIBLE (-6300 4150);
FORCEPROP 2 LAST CDS_LIB mstr_discrete
J 0
(-6350 3950);
PAINT ORANGE (-6350 3950);
DISPLAY INVISIBLE (-6350 3950);
FORCEPROP 2 LAST CDS_LOCATION C4C6
J 0
(-6300 4050);
DISPLAY 0.617021 (-6300 4050);
PAINT AQUA (-6300 4050);
DISPLAY INVISIBLE (-6300 4050);
FORCEADD OFFPAGE..2
(-3750 2025);
FORCEPROP 2 LAST $XR0 39 
J 0
(-3561 2025);
DISPLAY 0.638298 (-3561 2025);
PAINT MONO (-3561 2025);
FORCEPROP 2 LAST BOM_COST PROC_VRD_VCCIN_CPU0
J 0
(-3425 2075);
PAINT MONO (-3425 2075);
DISPLAY INVISIBLE (-3425 2075);
FORCEPROP 2 LAST PATH I22
J 0
(-3585 2085);
DISPLAY 1.021277 (-3585 2085);
PAINT ORANGE (-3585 2085);
DISPLAY INVISIBLE (-3585 2085);
FORCEPROP 2 LAST CDS_LIB mstr_standard
J 0
(-3750 2025);
PAINT ORANGE (-3750 2025);
DISPLAY INVISIBLE (-3750 2025);
FORCEPROP 1 LAST OFFPAGE TRUE
J 0
(-3425 1900);
DISPLAY 0.893617 (-3425 1900);
PAINT GREEN (-3425 1900);
DISPLAY INVISIBLE (-3425 1900);
FORCEPROP 1 LAST COMMENT_BODY TRUE
J 0
(-3795 1930);
DISPLAY 0.893617 (-3795 1930);
PAINT GREEN (-3795 1930);
DISPLAY INVISIBLE (-3795 1930);
FORCEPROP 2 LAST ROOM PVSA_CPU0_VSENSE_VR
J 0
(-4150 2100);
PAINT ORANGE (-4150 2100);
DISPLAY INVISIBLE (-4150 2100);
FORCEADD PVSA_CPU0..1
(-4300 2650);
FORCEPROP 3 LASTPIN (-4300 2600) SIG_NAME PVSA_CPU0\g
J 0
(-4290 2610);
DISPLAY 0.659574 (-4290 2610);
PAINT MONO (-4290 2610);
DISPLAY INVISIBLE (-4290 2610);
FORCEPROP 2 LAST ROOM PVSA_CPU0_VSENSE_VR
J 0
(-4050 2750);
PAINT ORANGE (-4050 2750);
DISPLAY INVISIBLE (-4050 2750);
FORCEPROP 1 LAST HDL_POWER PVSA_CPU0
J 1
(-4300 2700);
DISPLAY 0.872340 (-4300 2700);
PAINT GREEN (-4300 2700);
DISPLAY INVISIBLE (-4300 2700);
FORCEPROP 1 LAST PATH I23
J 0
(-4250 2675);
DISPLAY 0.872340 (-4250 2675);
PAINT AQUA (-4250 2675);
DISPLAY INVISIBLE (-4250 2675);
FORCEPROP 1 LAST BODY_TYPE PLUMBING
J 0
(-4345 2607);
DISPLAY 0.340426 (-4345 2607);
PAINT GREEN (-4345 2607);
DISPLAY INVISIBLE (-4345 2607);
FORCEPROP 2 LAST CDS_LIB mstr_symbols
J 0
(-4300 2650);
PAINT ORANGE (-4300 2650);
DISPLAY INVISIBLE (-4300 2650);
FORCEPROP 2 LAST BOM_COST PROC_VRD_VCCIN_CPU0
J 0
(-4275 2750);
PAINT MONO (-4275 2750);
DISPLAY INVISIBLE (-4275 2750);
FORCEPROP 1 LAST VOLTAGE 1.1V
J 0
(-4345 2607);
DISPLAY 0.340426 (-4345 2607);
PAINT SKYBLUE (-4345 2607);
DISPLAY INVISIBLE (-4345 2607);
FORCEADD RES..1
(-5100 2425);
FORCEPROP 1 LAST PACK_TYPE 0402
J 0
(-5175 2250);
DISPLAY 0.617021 (-5175 2250);
PAINT SKYBLUE (-5175 2250);
FORCEPROP 1 LASTPIN (-5200 2425) $PN 1
J 0
(-5188 2437);
DISPLAY 0.617021 (-5188 2437);
PAINT ORANGE (-5188 2437);
FORCEPROP 1 LAST WATTAGE 1/16W
J 2
(-5100 2300);
DISPLAY 0.617021 (-5100 2300);
PAINT SKYBLUE (-5100 2300);
FORCEPROP 1 LAST TOLERANCE 1%
J 0
(-5050 2350);
DISPLAY 0.617021 (-5050 2350);
PAINT SKYBLUE (-5050 2350);
FORCEPROP 1 LASTPIN (-5000 2425) $PN 2
J 0
(-5038 2437);
DISPLAY 0.617021 (-5038 2437);
PAINT ORANGE (-5038 2437);
FORCEPROP 1 LAST PART_NUMBER G21796-017
J 0
(-5150 2525);
DISPLAY 0.617021 (-5150 2525);
PAINT BLUE (-5150 2525);
FORCEPROP 1 LAST LOCATION R4C5
J 0
(-5150 2475);
DISPLAY 0.617021 (-5150 2475);
PAINT AQUA (-5150 2475);
FORCEPROP 1 LAST VALUE 100.0
J 2
(-5100 2350);
DISPLAY 0.617021 (-5100 2350);
PAINT SKYBLUE (-5100 2350);
FORCEPROP 2 LAST CDS_LIB mstr_discrete
J 0
(-5100 2425);
PAINT ORANGE (-5100 2425);
DISPLAY INVISIBLE (-5100 2425);
FORCEPROP 1 LAST MATERIAL CHIP
J 0
(-5075 2300);
PAINT SKYBLUE (-5075 2300);
DISPLAY INVISIBLE (-5075 2300);
FORCEPROP 2 LAST SEC_TYPE 0402
J 0
(-5135 2635);
DISPLAY 1.021277 (-5135 2635);
PAINT ORANGE (-5135 2635);
DISPLAY INVISIBLE (-5135 2635);
FORCEPROP 2 LAST SEC 1
J 0
(-5135 2635);
DISPLAY 0.680851 (-5135 2635);
PAINT MONO (-5135 2635);
DISPLAY INVISIBLE (-5135 2635);
FORCEPROP 2 LAST BOM_COST PROC_VRD_VCCIN_CPU0
J 0
(-5150 2575);
PAINT MONO (-5150 2575);
DISPLAY INVISIBLE (-5150 2575);
FORCEPROP 1 LAST PATH I24
J 0
(-5150 2575);
DISPLAY 0.978723 (-5150 2575);
PAINT WHITE (-5150 2575);
DISPLAY INVISIBLE (-5150 2575);
FORCEPROP 2 LAST ROOM PVSA_CPU0_VSENSE_VR
J 0
(-5150 2525);
PAINT ORANGE (-5150 2525);
DISPLAY INVISIBLE (-5150 2525);
FORCEPROP 2 LAST CDS_LOCATION R4C5
J 0
(-5150 2475);
DISPLAY 0.617021 (-5150 2475);
PAINT AQUA (-5150 2475);
DISPLAY INVISIBLE (-5150 2475);
FORCEADD CAP..1
R 2
(-6400 3350);
FORCEPROP 1 LAST VALUE 0.220UF
J 2
(-6450 3400);
DISPLAY 0.617021 (-6450 3400);
PAINT SKYBLUE (-6450 3400);
FORCEPROP 1 LAST PART_NUMBER A36096-104
J 2
(-6450 3200);
DISPLAY 0.617021 (-6450 3200);
PAINT BLUE (-6450 3200);
FORCEPROP 1 LASTPIN (-6400 3250) $PN 2
J 2
(-6410 3230);
DISPLAY 0.617021 (-6410 3230);
PAINT ORANGE (-6410 3230);
FORCEPROP 1 LAST PACK_TYPE 0402
J 2
(-6450 3150);
DISPLAY 0.617021 (-6450 3150);
PAINT SKYBLUE (-6450 3150);
FORCEPROP 1 LAST MATERIAL X7R
J 2
(-6450 3250);
DISPLAY 0.617021 (-6450 3250);
PAINT SKYBLUE (-6450 3250);
FORCEPROP 1 LAST TOLERANCE 10%
J 2
(-6450 3300);
DISPLAY 0.617021 (-6450 3300);
PAINT SKYBLUE (-6450 3300);
FORCEPROP 1 LAST LOCATION C4C8
J 2
(-6450 3450);
DISPLAY 0.617021 (-6450 3450);
PAINT AQUA (-6450 3450);
FORCEPROP 1 LAST VOLTAGE 16V
J 2
(-6450 3350);
DISPLAY 0.617021 (-6450 3350);
PAINT SKYBLUE (-6450 3350);
FORCEPROP 1 LASTPIN (-6400 3450) $PN 1
J 2
(-6410 3430);
DISPLAY 0.617021 (-6410 3430);
PAINT ORANGE (-6410 3430);
FORCEPROP 2 LAST CDS_LIB mstr_discrete
J 0
(-6400 3350);
PAINT ORANGE (-6400 3350);
DISPLAY INVISIBLE (-6400 3350);
FORCEPROP 2 LAST CDS_LOCATION C4C8
J 2
(-6450 3450);
DISPLAY 0.617021 (-6450 3450);
PAINT AQUA (-6450 3450);
DISPLAY INVISIBLE (-6450 3450);
FORCEPROP 1 LAST PATH I25
J 2
(-6450 3500);
DISPLAY 0.978723 (-6450 3500);
PAINT WHITE (-6450 3500);
DISPLAY INVISIBLE (-6450 3500);
FORCEPROP 2 LAST ROOM PVSA_CPU0_PWR_VR
J 0
(-6450 3500);
DISPLAY 1.361702 (-6450 3500);
PAINT ORANGE (-6450 3500);
DISPLAY INVISIBLE (-6450 3500);
FORCEPROP 0 LAST SPOF TRUE
J 0
(-6450 3550);
DISPLAY 1.021277 (-6450 3550);
PAINT ORANGE (-6450 3550);
DISPLAY INVISIBLE (-6450 3550);
FORCEPROP 2 LAST SEC_TYPE 0402
J 0
(-6450 3550);
DISPLAY 1.021277 (-6450 3550);
PAINT ORANGE (-6450 3550);
DISPLAY INVISIBLE (-6450 3550);
FORCEPROP 2 LAST SEC 1
J 0
(-6450 3550);
DISPLAY 0.680851 (-6450 3550);
PAINT MONO (-6450 3550);
DISPLAY INVISIBLE (-6450 3550);
FORCEADD RES..1
(-5075 2025);
FORCEPROP 1 LAST VALUE 0.0
J 2
(-5100 1950);
DISPLAY 0.617021 (-5100 1950);
PAINT SKYBLUE (-5100 1950);
FORCEPROP 1 LASTPIN (-5175 2025) $PN 1
J 0
(-5163 2037);
DISPLAY 0.617021 (-5163 2037);
PAINT ORANGE (-5163 2037);
FORCEPROP 1 LAST LOCATION R4C4
J 0
(-5125 2075);
DISPLAY 0.617021 (-5125 2075);
PAINT AQUA (-5125 2075);
FORCEPROP 1 LAST PART_NUMBER G21497-005
J 0
(-5200 2125);
DISPLAY 0.617021 (-5200 2125);
PAINT BLUE (-5200 2125);
FORCEPROP 1 LASTPIN (-4975 2025) $PN 2
J 0
(-5013 2037);
DISPLAY 0.617021 (-5013 2037);
PAINT ORANGE (-5013 2037);
FORCEPROP 1 LAST TOLERANCE 5%
J 0
(-5075 1950);
DISPLAY 0.617021 (-5075 1950);
PAINT SKYBLUE (-5075 1950);
FORCEPROP 1 LAST MATERIAL CHIP
J 0
(-5075 1875);
DISPLAY 0.617021 (-5075 1875);
PAINT SKYBLUE (-5075 1875);
FORCEPROP 1 LAST PACK_TYPE 0402
J 0
(-5200 1825);
DISPLAY 0.617021 (-5200 1825);
PAINT SKYBLUE (-5200 1825);
FORCEPROP 1 LAST WATTAGE 1/16W
J 2
(-5100 1875);
DISPLAY 0.617021 (-5100 1875);
PAINT SKYBLUE (-5100 1875);
FORCEPROP 2 LAST SEC 1
J 0
(-5110 2235);
DISPLAY 0.680851 (-5110 2235);
PAINT MONO (-5110 2235);
DISPLAY INVISIBLE (-5110 2235);
FORCEPROP 2 LAST SEC_TYPE 0402
J 0
(-5110 2235);
DISPLAY 1.021277 (-5110 2235);
PAINT ORANGE (-5110 2235);
DISPLAY INVISIBLE (-5110 2235);
FORCEPROP 2 LAST BOM_COST PROC_VRD_VCCIN_CPU0
J 0
(-5200 2175);
PAINT MONO (-5200 2175);
DISPLAY INVISIBLE (-5200 2175);
FORCEPROP 2 LAST CDS_LOCATION R4C4
J 0
(-5125 2075);
DISPLAY 0.617021 (-5125 2075);
PAINT AQUA (-5125 2075);
DISPLAY INVISIBLE (-5125 2075);
FORCEPROP 1 LAST PATH I26
J 0
(-5125 2175);
DISPLAY 0.978723 (-5125 2175);
PAINT WHITE (-5125 2175);
DISPLAY INVISIBLE (-5125 2175);
FORCEPROP 2 LAST ROOM PVSA_CPU0_VSENSE_VR
J 0
(-5125 2125);
PAINT ORANGE (-5125 2125);
DISPLAY INVISIBLE (-5125 2125);
FORCEPROP 2 LAST CDS_LIB mstr_discrete
J 0
(-5075 2025);
PAINT ORANGE (-5075 2025);
DISPLAY INVISIBLE (-5075 2025);
FORCEADD OFFPAGE..2
(-3750 1575);
FORCEPROP 2 LAST $XR0 39 
J 0
(-3561 1575);
DISPLAY 0.638298 (-3561 1575);
PAINT MONO (-3561 1575);
FORCEPROP 2 LAST BOM_COST PROC_VRD_VCCIN_CPU0
J 0
(-3550 1625);
PAINT MONO (-3550 1625);
DISPLAY INVISIBLE (-3550 1625);
FORCEPROP 1 LAST OFFPAGE TRUE
J 0
(-3425 1450);
DISPLAY 0.893617 (-3425 1450);
PAINT GREEN (-3425 1450);
DISPLAY INVISIBLE (-3425 1450);
FORCEPROP 2 LAST PATH I27
J 0
(-3585 1635);
DISPLAY 1.021277 (-3585 1635);
PAINT ORANGE (-3585 1635);
DISPLAY INVISIBLE (-3585 1635);
FORCEPROP 2 LAST CDS_LIB mstr_standard
J 0
(-3750 1575);
PAINT ORANGE (-3750 1575);
DISPLAY INVISIBLE (-3750 1575);
FORCEPROP 1 LAST COMMENT_BODY TRUE
J 0
(-3795 1480);
DISPLAY 0.893617 (-3795 1480);
PAINT GREEN (-3795 1480);
DISPLAY INVISIBLE (-3795 1480);
FORCEPROP 2 LAST ROOM PVSA_CPU0_VSENSE_VR
J 0
(-4150 1650);
PAINT ORANGE (-4150 1650);
DISPLAY INVISIBLE (-4150 1650);
FORCEADD GND..1
(-4250 1050);
FORCEPROP 3 LASTPIN (-4250 1100) SIG_NAME GND\g
J 0
(-4240 1110);
DISPLAY 0.659574 (-4240 1110);
PAINT MONO (-4240 1110);
DISPLAY INVISIBLE (-4240 1110);
FORCEPROP 1 LAST HDL_POWER GND
J 0
(-4250 1200);
DISPLAY 0.893617 (-4250 1200);
PAINT GREEN (-4250 1200);
DISPLAY INVISIBLE (-4250 1200);
FORCEPROP 1 LAST PATH I28
J 0
(-4175 1050);
DISPLAY 0.872340 (-4175 1050);
PAINT AQUA (-4175 1050);
DISPLAY INVISIBLE (-4175 1050);
FORCEPROP 2 LAST CDS_LIB mstr_symbols
J 0
(-4250 1050);
PAINT ORANGE (-4250 1050);
DISPLAY INVISIBLE (-4250 1050);
FORCEPROP 1 LAST VOLTAGE 0
J 0
(-4250 1050);
PAINT SKYBLUE (-4250 1050);
DISPLAY INVISIBLE (-4250 1050);
FORCEPROP 2 LAST BOM_COST PROC_VRD_VCCIN_CPU0
J 0
(-4625 1125);
PAINT MONO (-4625 1125);
DISPLAY INVISIBLE (-4625 1125);
FORCEPROP 2 LAST ROOM PVSA_CPU0_VSENSE_VR
J 0
(-4800 1125);
PAINT ORANGE (-4800 1125);
DISPLAY INVISIBLE (-4800 1125);
FORCEPROP 1 LAST SIZE 1B
J 0
(-4175 1000);
DISPLAY 0.893617 (-4175 1000);
PAINT GREEN (-4175 1000);
DISPLAY INVISIBLE (-4175 1000);
FORCEPROP 1 LAST BODY_TYPE PLUMBING
J 0
(-4295 1007);
DISPLAY 0.340426 (-4295 1007);
PAINT GREEN (-4295 1007);
DISPLAY INVISIBLE (-4295 1007);
FORCEADD RES..1
(-5075 1200);
FORCEPROP 1 LAST PACK_TYPE 0402
J 0
(-5150 1025);
DISPLAY 0.617021 (-5150 1025);
PAINT SKYBLUE (-5150 1025);
FORCEPROP 1 LAST VALUE 100.0
J 2
(-5075 1125);
DISPLAY 0.617021 (-5075 1125);
PAINT SKYBLUE (-5075 1125);
FORCEPROP 1 LAST LOCATION R4C1
J 0
(-5125 1250);
DISPLAY 0.617021 (-5125 1250);
PAINT AQUA (-5125 1250);
FORCEPROP 1 LAST PART_NUMBER G21796-017
J 0
(-5125 1300);
DISPLAY 0.617021 (-5125 1300);
PAINT BLUE (-5125 1300);
FORCEPROP 1 LAST TOLERANCE 1%
J 0
(-5025 1125);
DISPLAY 0.617021 (-5025 1125);
PAINT SKYBLUE (-5025 1125);
FORCEPROP 1 LASTPIN (-4975 1200) $PN 2
J 0
(-5013 1212);
DISPLAY 0.617021 (-5013 1212);
PAINT ORANGE (-5013 1212);
FORCEPROP 1 LAST WATTAGE 1/16W
J 2
(-5075 1075);
DISPLAY 0.617021 (-5075 1075);
PAINT SKYBLUE (-5075 1075);
FORCEPROP 1 LASTPIN (-5175 1200) $PN 1
J 0
(-5163 1212);
DISPLAY 0.617021 (-5163 1212);
PAINT ORANGE (-5163 1212);
FORCEPROP 2 LAST SEC_TYPE 0402
J 0
(-5110 1410);
DISPLAY 1.021277 (-5110 1410);
PAINT ORANGE (-5110 1410);
DISPLAY INVISIBLE (-5110 1410);
FORCEPROP 2 LAST SEC 1
J 0
(-5110 1410);
DISPLAY 0.680851 (-5110 1410);
PAINT MONO (-5110 1410);
DISPLAY INVISIBLE (-5110 1410);
FORCEPROP 1 LAST MATERIAL CHIP
J 0
(-5050 1075);
PAINT SKYBLUE (-5050 1075);
DISPLAY INVISIBLE (-5050 1075);
FORCEPROP 2 LAST CDS_LIB mstr_discrete
J 0
(-5075 1200);
PAINT ORANGE (-5075 1200);
DISPLAY INVISIBLE (-5075 1200);
FORCEPROP 2 LAST ROOM PVSA_CPU0_VSENSE_VR
J 0
(-5125 1300);
PAINT ORANGE (-5125 1300);
DISPLAY INVISIBLE (-5125 1300);
FORCEPROP 1 LAST PATH I29
J 0
(-5125 1350);
DISPLAY 0.978723 (-5125 1350);
PAINT WHITE (-5125 1350);
DISPLAY INVISIBLE (-5125 1350);
FORCEPROP 2 LAST CDS_LOCATION R4C1
J 0
(-5125 1250);
DISPLAY 0.617021 (-5125 1250);
PAINT AQUA (-5125 1250);
DISPLAY INVISIBLE (-5125 1250);
FORCEPROP 2 LAST BOM_COST PROC_VRD_VCCIN_CPU0
J 0
(-5125 1350);
PAINT MONO (-5125 1350);
DISPLAY INVISIBLE (-5125 1350);
FORCEADD OFFPAGE..2
(-1875 3925);
FORCEPROP 2 LAST $XR0 201 
J 0
(-1686 3925);
DISPLAY 0.638298 (-1686 3925);
PAINT MONO (-1686 3925);
FORCEPROP 2 LAST BOM_COST PROC_VRD_VCCIN_CPU0
J 0
(-1675 3975);
DISPLAY 1.446809 (-1675 3975);
PAINT MONO (-1675 3975);
DISPLAY INVISIBLE (-1675 3975);
FORCEPROP 1 LAST OFFPAGE TRUE
J 0
(-1550 3800);
DISPLAY 1.723404 (-1550 3800);
PAINT GREEN (-1550 3800);
DISPLAY INVISIBLE (-1550 3800);
FORCEPROP 2 LAST PATH I3
J 0
(-1695 4000);
DISPLAY 1.021277 (-1695 4000);
PAINT ORANGE (-1695 4000);
DISPLAY INVISIBLE (-1695 4000);
FORCEPROP 2 LAST CDS_LIB mstr_standard
J 0
(-1875 3925);
PAINT ORANGE (-1875 3925);
DISPLAY INVISIBLE (-1875 3925);
FORCEPROP 1 LAST COMMENT_BODY TRUE
J 0
(-1920 3830);
DISPLAY 1.723404 (-1920 3830);
PAINT GREEN (-1920 3830);
DISPLAY INVISIBLE (-1920 3830);
FORCEPROP 2 LAST ROOM PVSA_CPU0_PWR_VR
J 0
(-2275 4000);
DISPLAY 1.936170 (-2275 4000);
PAINT ORANGE (-2275 4000);
DISPLAY INVISIBLE (-2275 4000);
FORCEADD RES..1
(-5075 1575);
FORCEPROP 1 LAST WATTAGE 1/16W
J 2
(-5100 1425);
DISPLAY 0.617021 (-5100 1425);
PAINT SKYBLUE (-5100 1425);
FORCEPROP 1 LAST PART_NUMBER G21497-005
J 0
(-5200 1675);
DISPLAY 0.617021 (-5200 1675);
PAINT BLUE (-5200 1675);
FORCEPROP 1 LAST PACK_TYPE 0402
J 0
(-5200 1375);
DISPLAY 0.617021 (-5200 1375);
PAINT SKYBLUE (-5200 1375);
FORCEPROP 1 LASTPIN (-4975 1575) $PN 2
J 0
(-5013 1587);
DISPLAY 0.617021 (-5013 1587);
PAINT ORANGE (-5013 1587);
FORCEPROP 1 LAST TOLERANCE 5%
J 0
(-5075 1500);
DISPLAY 0.617021 (-5075 1500);
PAINT SKYBLUE (-5075 1500);
FORCEPROP 1 LAST MATERIAL CHIP
J 0
(-5075 1425);
DISPLAY 0.617021 (-5075 1425);
PAINT SKYBLUE (-5075 1425);
FORCEPROP 1 LAST LOCATION R4C2
J 0
(-5125 1625);
DISPLAY 0.617021 (-5125 1625);
PAINT AQUA (-5125 1625);
FORCEPROP 1 LAST VALUE 0.0
J 2
(-5100 1500);
DISPLAY 0.617021 (-5100 1500);
PAINT SKYBLUE (-5100 1500);
FORCEPROP 1 LASTPIN (-5175 1575) $PN 1
J 0
(-5163 1587);
DISPLAY 0.617021 (-5163 1587);
PAINT ORANGE (-5163 1587);
FORCEPROP 2 LAST SEC_TYPE 0402
J 0
(-5110 1785);
DISPLAY 1.021277 (-5110 1785);
PAINT ORANGE (-5110 1785);
DISPLAY INVISIBLE (-5110 1785);
FORCEPROP 2 LAST SEC 1
J 0
(-5110 1785);
DISPLAY 0.680851 (-5110 1785);
PAINT MONO (-5110 1785);
DISPLAY INVISIBLE (-5110 1785);
FORCEPROP 2 LAST CDS_LIB mstr_discrete
J 0
(-5075 1575);
PAINT ORANGE (-5075 1575);
DISPLAY INVISIBLE (-5075 1575);
FORCEPROP 2 LAST ROOM PVSA_CPU0_VSENSE_VR
J 0
(-5125 1675);
PAINT ORANGE (-5125 1675);
DISPLAY INVISIBLE (-5125 1675);
FORCEPROP 1 LAST PATH I30
J 0
(-5125 1725);
DISPLAY 0.978723 (-5125 1725);
PAINT WHITE (-5125 1725);
DISPLAY INVISIBLE (-5125 1725);
FORCEPROP 2 LAST CDS_LOCATION R4C2
J 0
(-5125 1625);
DISPLAY 0.617021 (-5125 1625);
PAINT AQUA (-5125 1625);
DISPLAY INVISIBLE (-5125 1625);
FORCEPROP 2 LAST BOM_COST PROC_VRD_VCCIN_CPU0
J 0
(-5200 1725);
PAINT MONO (-5200 1725);
DISPLAY INVISIBLE (-5200 1725);
FORCEADD CAP_A..1
(-6600 4000);
FORCEPROP 1 LAST PACK_TYPE 0402V
J 0
(-6550 3800);
DISPLAY 0.617021 (-6550 3800);
PAINT SKYBLUE (-6550 3800);
FORCEPROP 1 LAST LOCATION C4C10
J 0
(-6550 4100);
DISPLAY 0.617021 (-6550 4100);
PAINT AQUA (-6550 4100);
FORCEPROP 1 LASTPIN (-6600 4100) $PN 1
J 0
(-6590 4080);
DISPLAY 0.617021 (-6590 4080);
PAINT ORANGE (-6590 4080);
FORCEPROP 1 LAST PART_NUMBER A36096-030
J 0
(-6550 3850);
DISPLAY 0.617021 (-6550 3850);
PAINT BLUE (-6550 3850);
FORCEPROP 1 LASTPIN (-6600 3900) $PN 2
J 0
(-6590 3880);
DISPLAY 0.617021 (-6590 3880);
PAINT ORANGE (-6590 3880);
FORCEPROP 1 LAST MATERIAL X7R
J 0
(-6550 3900);
DISPLAY 0.617021 (-6550 3900);
PAINT SKYBLUE (-6550 3900);
FORCEPROP 1 LAST VOLTAGE 16V
J 0
(-6550 4000);
DISPLAY 0.617021 (-6550 4000);
PAINT SKYBLUE (-6550 4000);
FORCEPROP 1 LAST TOLERANCE 10%
J 0
(-6550 3950);
DISPLAY 0.617021 (-6550 3950);
PAINT SKYBLUE (-6550 3950);
FORCEPROP 1 LAST VALUE 0.1UF
J 0
(-6550 4050);
DISPLAY 0.617021 (-6550 4050);
PAINT SKYBLUE (-6550 4050);
FORCEPROP 2 LAST SEC 1
J 0
(-6550 4200);
DISPLAY 0.680851 (-6550 4200);
PAINT MONO (-6550 4200);
DISPLAY INVISIBLE (-6550 4200);
FORCEPROP 2 LAST SEC_TYPE 0402V
J 0
(-6550 4200);
DISPLAY 1.021277 (-6550 4200);
PAINT ORANGE (-6550 4200);
DISPLAY INVISIBLE (-6550 4200);
FORCEPROP 2 LAST CDS_SEC 1
J 0
(-6550 4150);
PAINT ORANGE (-6550 4150);
DISPLAY INVISIBLE (-6550 4150);
FORCEPROP 2 LAST CDS_LOCATION C4C10
J 0
(-6550 4100);
DISPLAY 0.617021 (-6550 4100);
PAINT AQUA (-6550 4100);
DISPLAY INVISIBLE (-6550 4100);
FORCEPROP 2 LAST ROOM PVSA_CPU0_PWR_VR
J 0
(-6550 4150);
DISPLAY 1.361702 (-6550 4150);
PAINT ORANGE (-6550 4150);
DISPLAY INVISIBLE (-6550 4150);
FORCEPROP 1 LAST PATH I31
J 0
(-6550 4150);
DISPLAY 0.978723 (-6550 4150);
PAINT WHITE (-6550 4150);
DISPLAY INVISIBLE (-6550 4150);
FORCEPROP 2 LAST CDS_LIB dev_discrete
J 0
(-6600 4000);
PAINT ORANGE (-6600 4000);
DISPLAY INVISIBLE (-6600 4000);
FORCEADD CAP..1
(-6850 3950);
FORCEPROP 1 LAST PART_NUMBER D97712-011
J 0
(-6800 3800);
DISPLAY 0.617021 (-6800 3800);
PAINT BLUE (-6800 3800);
FORCEPROP 1 LAST VOLTAGE 16V
J 0
(-6800 3950);
DISPLAY 0.617021 (-6800 3950);
PAINT SKYBLUE (-6800 3950);
FORCEPROP 1 LAST VALUE 1.0UF
J 0
(-6800 4000);
DISPLAY 0.617021 (-6800 4000);
PAINT SKYBLUE (-6800 4000);
FORCEPROP 1 LAST LOCATION C4C9
J 0
(-6800 4050);
DISPLAY 0.617021 (-6800 4050);
PAINT AQUA (-6800 4050);
FORCEPROP 1 LAST TOLERANCE 10%
J 0
(-6800 3900);
DISPLAY 0.617021 (-6800 3900);
PAINT SKYBLUE (-6800 3900);
FORCEPROP 1 LAST MATERIAL X6S
J 0
(-6800 3850);
DISPLAY 0.617021 (-6800 3850);
PAINT SKYBLUE (-6800 3850);
FORCEPROP 1 LASTPIN (-6850 4050) $PN 1
J 0
(-6840 4030);
DISPLAY 0.617021 (-6840 4030);
PAINT ORANGE (-6840 4030);
FORCEPROP 1 LASTPIN (-6850 3850) $PN 2
J 0
(-6840 3830);
DISPLAY 0.617021 (-6840 3830);
PAINT ORANGE (-6840 3830);
FORCEPROP 1 LAST PACK_TYPE 0402
J 0
(-6800 3750);
DISPLAY 0.617021 (-6800 3750);
PAINT SKYBLUE (-6800 3750);
FORCEPROP 2 LAST SEC_TYPE 0402
J 0
(-6800 4150);
DISPLAY 1.021277 (-6800 4150);
PAINT ORANGE (-6800 4150);
DISPLAY INVISIBLE (-6800 4150);
FORCEPROP 2 LAST SEC 1
J 0
(-6800 4150);
DISPLAY 0.680851 (-6800 4150);
PAINT MONO (-6800 4150);
DISPLAY INVISIBLE (-6800 4150);
FORCEPROP 1 LAST PATH I32
J 0
(-6800 4100);
DISPLAY 0.978723 (-6800 4100);
PAINT WHITE (-6800 4100);
DISPLAY INVISIBLE (-6800 4100);
FORCEPROP 2 LAST ROOM PVSA_CPU0_PWR_VR
J 0
(-6800 4100);
DISPLAY 1.361702 (-6800 4100);
PAINT ORANGE (-6800 4100);
DISPLAY INVISIBLE (-6800 4100);
FORCEPROP 2 LAST CDS_LIB mstr_discrete
J 0
(-6850 3950);
PAINT ORANGE (-6850 3950);
DISPLAY INVISIBLE (-6850 3950);
FORCEPROP 2 LAST CDS_LOCATION C4C9
J 0
(-6800 4050);
DISPLAY 0.617021 (-6800 4050);
PAINT AQUA (-6800 4050);
DISPLAY INVISIBLE (-6800 4050);
FORCEADD CAP..1
(-7100 3975);
FORCEPROP 1 LAST LOCATION C6N2
J 0
(-7050 4075);
DISPLAY 0.617021 (-7050 4075);
PAINT AQUA (-7050 4075);
FORCEPROP 1 LAST PART_NUMBER C95333-007
J 0
(-7050 3825);
DISPLAY 0.617021 (-7050 3825);
PAINT BLUE (-7050 3825);
FORCEPROP 1 LAST TOLERANCE 10%
J 0
(-7050 3925);
DISPLAY 0.617021 (-7050 3925);
PAINT SKYBLUE (-7050 3925);
FORCEPROP 1 LAST VALUE 10UF
J 0
(-7050 4025);
DISPLAY 0.617021 (-7050 4025);
PAINT SKYBLUE (-7050 4025);
FORCEPROP 1 LAST VOLTAGE 16V
J 0
(-7050 3975);
DISPLAY 0.617021 (-7050 3975);
PAINT SKYBLUE (-7050 3975);
FORCEPROP 1 LAST MATERIAL X6S
J 0
(-7050 3875);
DISPLAY 0.617021 (-7050 3875);
PAINT SKYBLUE (-7050 3875);
FORCEPROP 1 LASTPIN (-7100 3875) $PN 2
J 0
(-7090 3855);
DISPLAY 0.617021 (-7090 3855);
PAINT ORANGE (-7090 3855);
FORCEPROP 1 LASTPIN (-7100 4075) $PN 1
J 0
(-7090 4055);
DISPLAY 0.617021 (-7090 4055);
PAINT ORANGE (-7090 4055);
FORCEPROP 1 LAST PACK_TYPE 0805
J 0
(-7050 3775);
DISPLAY 0.617021 (-7050 3775);
PAINT SKYBLUE (-7050 3775);
FORCEPROP 2 LAST SEC_TYPE 0805
J 0
(-7050 4175);
DISPLAY 1.021277 (-7050 4175);
PAINT ORANGE (-7050 4175);
DISPLAY INVISIBLE (-7050 4175);
FORCEPROP 2 LAST SEC 1
J 0
(-7050 4175);
DISPLAY 0.680851 (-7050 4175);
PAINT MONO (-7050 4175);
DISPLAY INVISIBLE (-7050 4175);
FORCEPROP 1 LAST PATH I33
J 0
(-7050 4125);
DISPLAY 0.978723 (-7050 4125);
PAINT WHITE (-7050 4125);
DISPLAY INVISIBLE (-7050 4125);
FORCEPROP 2 LAST ROOM PVSA_CPU0_PWR_VR
J 0
(-7050 4125);
DISPLAY 1.361702 (-7050 4125);
PAINT ORANGE (-7050 4125);
DISPLAY INVISIBLE (-7050 4125);
FORCEPROP 2 LAST CDS_LOCATION C6N2
J 0
(-7050 4075);
DISPLAY 0.617021 (-7050 4075);
PAINT AQUA (-7050 4075);
DISPLAY INVISIBLE (-7050 4075);
FORCEPROP 2 LAST CDS_LIB mstr_discrete
J 0
(-7100 3975);
PAINT ORANGE (-7100 3975);
DISPLAY INVISIBLE (-7100 3975);
FORCEADD CAP..1
(-7325 3950);
FORCEPROP 1 LAST LOCATION C6N3
J 0
(-7275 4050);
DISPLAY 0.617021 (-7275 4050);
PAINT AQUA (-7275 4050);
FORCEPROP 1 LAST PART_NUMBER C95333-007
J 0
(-7275 3800);
DISPLAY 0.617021 (-7275 3800);
PAINT BLUE (-7275 3800);
FORCEPROP 1 LAST VALUE 10UF
J 0
(-7275 4000);
DISPLAY 0.617021 (-7275 4000);
PAINT SKYBLUE (-7275 4000);
FORCEPROP 1 LAST PACK_TYPE 0805
J 0
(-7275 3750);
DISPLAY 0.617021 (-7275 3750);
PAINT SKYBLUE (-7275 3750);
FORCEPROP 1 LASTPIN (-7325 4050) $PN 1
J 0
(-7315 4030);
DISPLAY 0.617021 (-7315 4030);
PAINT ORANGE (-7315 4030);
FORCEPROP 1 LAST MATERIAL X6S
J 0
(-7275 3850);
DISPLAY 0.617021 (-7275 3850);
PAINT SKYBLUE (-7275 3850);
FORCEPROP 1 LAST VOLTAGE 16V
J 0
(-7275 3950);
DISPLAY 0.617021 (-7275 3950);
PAINT SKYBLUE (-7275 3950);
FORCEPROP 1 LAST TOLERANCE 10%
J 0
(-7275 3900);
DISPLAY 0.617021 (-7275 3900);
PAINT SKYBLUE (-7275 3900);
FORCEPROP 1 LASTPIN (-7325 3850) $PN 2
J 0
(-7315 3830);
DISPLAY 0.617021 (-7315 3830);
PAINT ORANGE (-7315 3830);
FORCEPROP 2 LAST SEC_TYPE 0805
J 0
(-7275 4150);
DISPLAY 1.021277 (-7275 4150);
PAINT ORANGE (-7275 4150);
DISPLAY INVISIBLE (-7275 4150);
FORCEPROP 2 LAST SEC 1
J 0
(-7275 4150);
DISPLAY 0.680851 (-7275 4150);
PAINT MONO (-7275 4150);
DISPLAY INVISIBLE (-7275 4150);
FORCEPROP 1 LAST PATH I34
J 0
(-7275 4100);
DISPLAY 0.978723 (-7275 4100);
PAINT WHITE (-7275 4100);
DISPLAY INVISIBLE (-7275 4100);
FORCEPROP 2 LAST ROOM PVSA_CPU0_PWR_VR
J 0
(-7275 4100);
DISPLAY 1.361702 (-7275 4100);
PAINT ORANGE (-7275 4100);
DISPLAY INVISIBLE (-7275 4100);
FORCEPROP 2 LAST CDS_LOCATION C6N3
J 0
(-7275 4050);
DISPLAY 0.617021 (-7275 4050);
PAINT AQUA (-7275 4050);
DISPLAY INVISIBLE (-7275 4050);
FORCEPROP 2 LAST CDS_LIB mstr_discrete
J 0
(-7325 3950);
PAINT ORANGE (-7325 3950);
DISPLAY INVISIBLE (-7325 3950);
FORCEADD CAP..1
(-7575 4000);
FORCEPROP 1 LAST LOCATION C6N6
J 0
(-7525 4100);
DISPLAY 0.617021 (-7525 4100);
PAINT AQUA (-7525 4100);
FORCEPROP 1 LASTPIN (-7575 4100) $PN 1
J 0
(-7565 4080);
DISPLAY 0.617021 (-7565 4080);
PAINT ORANGE (-7565 4080);
FORCEPROP 1 LAST PART_NUMBER C95333-007
J 0
(-7525 3850);
DISPLAY 0.617021 (-7525 3850);
PAINT BLUE (-7525 3850);
FORCEPROP 1 LAST VALUE 10UF
J 0
(-7525 4050);
DISPLAY 0.617021 (-7525 4050);
PAINT SKYBLUE (-7525 4050);
FORCEPROP 1 LAST PACK_TYPE 0805
J 0
(-7525 3800);
DISPLAY 0.617021 (-7525 3800);
PAINT SKYBLUE (-7525 3800);
FORCEPROP 1 LAST MATERIAL X6S
J 0
(-7525 3900);
DISPLAY 0.617021 (-7525 3900);
PAINT SKYBLUE (-7525 3900);
FORCEPROP 1 LAST VOLTAGE 16V
J 0
(-7525 4000);
DISPLAY 0.617021 (-7525 4000);
PAINT SKYBLUE (-7525 4000);
FORCEPROP 1 LASTPIN (-7575 3900) $PN 2
J 0
(-7565 3880);
DISPLAY 0.617021 (-7565 3880);
PAINT ORANGE (-7565 3880);
FORCEPROP 1 LAST TOLERANCE 10%
J 0
(-7525 3950);
DISPLAY 0.617021 (-7525 3950);
PAINT SKYBLUE (-7525 3950);
FORCEPROP 2 LAST CDS_LOCATION C6N6
J 0
(-7525 4100);
DISPLAY 0.617021 (-7525 4100);
PAINT AQUA (-7525 4100);
DISPLAY INVISIBLE (-7525 4100);
FORCEPROP 2 LAST SEC 1
J 0
(-7525 4200);
DISPLAY 0.680851 (-7525 4200);
PAINT MONO (-7525 4200);
DISPLAY INVISIBLE (-7525 4200);
FORCEPROP 2 LAST SEC_TYPE 0805
J 0
(-7525 4200);
DISPLAY 1.021277 (-7525 4200);
PAINT ORANGE (-7525 4200);
DISPLAY INVISIBLE (-7525 4200);
FORCEPROP 1 LAST PATH I35
J 0
(-7525 4150);
DISPLAY 0.978723 (-7525 4150);
PAINT WHITE (-7525 4150);
DISPLAY INVISIBLE (-7525 4150);
FORCEPROP 2 LAST ROOM PVSA_CPU0_PWR_VR
J 0
(-7525 4150);
DISPLAY 1.361702 (-7525 4150);
PAINT ORANGE (-7525 4150);
DISPLAY INVISIBLE (-7525 4150);
FORCEPROP 2 LAST CDS_LIB mstr_discrete
J 0
(-7575 4000);
PAINT ORANGE (-7575 4000);
DISPLAY INVISIBLE (-7575 4000);
FORCEADD VCC_CORE..1
(-7575 4475);
FORCEPROP 3 LASTPIN (-7575 4425) SIG_NAME VR_FET_SW_P12V_STBY_PVCCIN_CPU0\g
J 0
(-7565 4435);
DISPLAY 0.659574 (-7565 4435);
PAINT MONO (-7565 4435);
DISPLAY INVISIBLE (-7565 4435);
FORCEPROP 1 LAST HDL_POWER VR_FET_SW_P12V_STBY_PVCCIN_CPU0
J 1
(-7500 4525);
DISPLAY 0.617021 (-7500 4525);
PAINT GREEN (-7500 4525);
FORCEPROP 1 LAST PATH I36
J 0
(-7525 4500);
DISPLAY 0.872340 (-7525 4500);
PAINT AQUA (-7525 4500);
DISPLAY INVISIBLE (-7525 4500);
FORCEPROP 2 LAST CDS_LIB mstr_symbols
J 0
(-7575 4475);
PAINT ORANGE (-7575 4475);
DISPLAY INVISIBLE (-7575 4475);
FORCEADD RES..2
(-5750 1825);
FORCEPROP 1 LAST MATERIAL EMPTY
J 0
(-5710 1750);
DISPLAY 0.617021 (-5710 1750);
PAINT RED (-5710 1750);
FORCEPROP 1 LAST LOCATION R4C3
J 0
(-5705 1950);
DISPLAY 0.617021 (-5705 1950);
PAINT AQUA (-5705 1950);
FORCEPROP 1 LAST PART_NUMBER G21796-026
J 0
(-5710 1700);
DISPLAY 0.617021 (-5710 1700);
PAINT BLUE (-5710 1700);
FORCEPROP 1 LAST VALUE 1.00K
J 0
(-5705 1900);
DISPLAY 0.617021 (-5705 1900);
PAINT SKYBLUE (-5705 1900);
FORCEPROP 1 LAST PACK_TYPE 0402
J 0
(-5710 1650);
DISPLAY 0.617021 (-5710 1650);
PAINT SKYBLUE (-5710 1650);
FORCEPROP 1 LAST WATTAGE 1/16W
J 0
(-5710 1800);
DISPLAY 0.617021 (-5710 1800);
PAINT SKYBLUE (-5710 1800);
FORCEPROP 1 LAST TOLERANCE 1%
J 0
(-5705 1850);
DISPLAY 0.617021 (-5705 1850);
PAINT SKYBLUE (-5705 1850);
FORCEPROP 1 LASTPIN (-5750 1925) $PN 1
J 0
(-5745 1887);
DISPLAY 0.617021 (-5745 1887);
PAINT ORANGE (-5745 1887);
FORCEPROP 1 LASTPIN (-5750 1725) $PN 2
J 0
(-5745 1735);
DISPLAY 0.617021 (-5745 1735);
PAINT ORANGE (-5745 1735);
FORCEPROP 2 LAST NO_XNET_CONNECTION 1
J 0
(-5700 2050);
PAINT MONO (-5700 2050);
DISPLAY INVISIBLE (-5700 2050);
FORCEPROP 2 LAST SEC 1
J 0
(-5685 2060);
DISPLAY 0.680851 (-5685 2060);
PAINT MONO (-5685 2060);
DISPLAY INVISIBLE (-5685 2060);
FORCEPROP 2 LAST SEC_TYPE 0402
J 0
(-5685 2060);
DISPLAY 1.021277 (-5685 2060);
PAINT ORANGE (-5685 2060);
DISPLAY INVISIBLE (-5685 2060);
FORCEPROP 2 LAST BOM_COST PROC_VRD_VCCIN_CPU0
J 0
(-5700 2000);
PAINT MONO (-5700 2000);
DISPLAY INVISIBLE (-5700 2000);
FORCEPROP 2 LAST CDS_LOCATION R4C3
J 0
(-5705 1950);
DISPLAY 0.617021 (-5705 1950);
PAINT AQUA (-5705 1950);
DISPLAY INVISIBLE (-5705 1950);
FORCEPROP 1 LAST PATH I37
J 0
(-5700 2000);
DISPLAY 0.978723 (-5700 2000);
PAINT WHITE (-5700 2000);
DISPLAY INVISIBLE (-5700 2000);
FORCEPROP 2 LAST ROOM PVSA_CPU0_VSENSE_VR
J 0
(-5700 2000);
PAINT MONO (-5700 2000);
DISPLAY INVISIBLE (-5700 2000);
FORCEPROP 2 LAST CDS_LIB mstr_discrete
J 0
(-5750 1825);
PAINT ORANGE (-5750 1825);
DISPLAY INVISIBLE (-5750 1825);
FORCEADD OFFPAGE..1
(-6800 3625);
FORCEPROP 2 LAST $XR0 201 
J 0
(-7052 3625);
DISPLAY 0.638298 (-7052 3625);
PAINT MONO (-7052 3625);
FORCEPROP 1 LAST OFFPAGE TRUE
J 0
(-6475 3500);
DISPLAY 1.680851 (-6475 3500);
PAINT GREEN (-6475 3500);
DISPLAY INVISIBLE (-6475 3500);
FORCEPROP 2 LAST PATH I38
J 0
(-6745 3700);
DISPLAY 1.021277 (-6745 3700);
PAINT ORANGE (-6745 3700);
DISPLAY INVISIBLE (-6745 3700);
FORCEPROP 2 LAST CDS_LIB mstr_standard
J 0
(-6800 3625);
PAINT ORANGE (-6800 3625);
DISPLAY INVISIBLE (-6800 3625);
FORCEPROP 2 LAST BOM_COST PROC_VRD_VCCIN_CPU0
J 0
(-7050 3675);
DISPLAY 1.446809 (-7050 3675);
PAINT MONO (-7050 3675);
DISPLAY INVISIBLE (-7050 3675);
FORCEPROP 1 LAST COMMENT_BODY TRUE
J 0
(-6675 3525);
DISPLAY 1.680851 (-6675 3525);
PAINT GREEN (-6675 3525);
DISPLAY INVISIBLE (-6675 3525);
FORCEPROP 2 LAST ROOM PVSA_CPU0_PWR_VR
J 0
(-7200 3700);
DISPLAY 1.936170 (-7200 3700);
PAINT ORANGE (-7200 3700);
DISPLAY INVISIBLE (-7200 3700);
FORCEADD GND..1
(-7575 3550);
FORCEPROP 3 LASTPIN (-7575 3600) SIG_NAME GND\g
J 0
(-7565 3610);
DISPLAY 0.659574 (-7565 3610);
PAINT MONO (-7565 3610);
DISPLAY INVISIBLE (-7565 3610);
FORCEPROP 1 LAST HDL_POWER GND
J 0
(-7575 3700);
DISPLAY 1.723404 (-7575 3700);
PAINT GREEN (-7575 3700);
DISPLAY INVISIBLE (-7575 3700);
FORCEPROP 1 LAST VOLTAGE 0
J 0
(-7575 3550);
PAINT SKYBLUE (-7575 3550);
DISPLAY INVISIBLE (-7575 3550);
FORCEPROP 2 LAST CDS_LIB mstr_symbols
J 0
(-7575 3550);
PAINT ORANGE (-7575 3550);
DISPLAY INVISIBLE (-7575 3550);
FORCEPROP 1 LAST PATH I39
J 0
(-7500 3550);
DISPLAY 0.872340 (-7500 3550);
PAINT AQUA (-7500 3550);
DISPLAY INVISIBLE (-7500 3550);
FORCEPROP 1 LAST SIZE 1B
J 0
(-7500 3500);
DISPLAY 1.723404 (-7500 3500);
PAINT GREEN (-7500 3500);
DISPLAY INVISIBLE (-7500 3500);
FORCEPROP 1 LAST BODY_TYPE PLUMBING
J 0
(-7620 3507);
DISPLAY 0.340426 (-7620 3507);
PAINT GREEN (-7620 3507);
DISPLAY INVISIBLE (-7620 3507);
FORCEPROP 2 LAST BOM_COST PROC_VRD_VCCIN_CPU0
J 0
(-7950 3625);
DISPLAY 1.446809 (-7950 3625);
PAINT MONO (-7950 3625);
DISPLAY INVISIBLE (-7950 3625);
FORCEPROP 2 LAST ROOM PVSA_CPU0_PWR_VR
J 0
(-8125 3625);
DISPLAY 1.936170 (-8125 3625);
PAINT ORANGE (-8125 3625);
DISPLAY INVISIBLE (-8125 3625);
FORCEADD PVSA_CPU0..1
(-625 3525);
FORCEPROP 3 LASTPIN (-625 3475) SIG_NAME PVSA_CPU0\g
J 0
(-615 3485);
DISPLAY 0.659574 (-615 3485);
PAINT MONO (-615 3485);
DISPLAY INVISIBLE (-615 3485);
FORCEPROP 1 LAST PATH I4
J 0
(-575 3550);
DISPLAY 0.872340 (-575 3550);
PAINT AQUA (-575 3550);
DISPLAY INVISIBLE (-575 3550);
FORCEPROP 1 LAST HDL_POWER PVSA_CPU0
J 1
(-625 3575);
DISPLAY 0.872340 (-625 3575);
PAINT GREEN (-625 3575);
DISPLAY INVISIBLE (-625 3575);
FORCEPROP 2 LAST CDS_LIB mstr_symbols
J 0
(-625 3525);
PAINT ORANGE (-625 3525);
DISPLAY INVISIBLE (-625 3525);
FORCEPROP 1 LAST BODY_TYPE PLUMBING
J 0
(-670 3482);
DISPLAY 0.340426 (-670 3482);
PAINT GREEN (-670 3482);
DISPLAY INVISIBLE (-670 3482);
FORCEPROP 1 LAST VOLTAGE 1.1V
J 0
(-670 3482);
DISPLAY 0.340426 (-670 3482);
PAINT SKYBLUE (-670 3482);
DISPLAY INVISIBLE (-670 3482);
FORCEADD OFFPAGE..1
(-7200 2075);
FORCEPROP 2 LAST $XR0 201 
J 0
(-7452 2075);
DISPLAY 0.638298 (-7452 2075);
PAINT MONO (-7452 2075);
FORCEPROP 2 LAST PATH I40
J 0
(-7135 2135);
DISPLAY 1.021277 (-7135 2135);
PAINT ORANGE (-7135 2135);
DISPLAY INVISIBLE (-7135 2135);
FORCEPROP 2 LAST CDS_LIB mstr_standard
J 0
(-7200 2075);
PAINT ORANGE (-7200 2075);
DISPLAY INVISIBLE (-7200 2075);
FORCEPROP 2 LAST BOM_COST PROC_VRD_VCCIN_CPU0
J 0
(-7400 2125);
PAINT MONO (-7400 2125);
DISPLAY INVISIBLE (-7400 2125);
FORCEPROP 2 LAST ROOM PVSA_CPU0_VSENSE_VR
J 0
(-7725 2150);
PAINT ORANGE (-7725 2150);
DISPLAY INVISIBLE (-7725 2150);
FORCEPROP 1 LAST OFFPAGE TRUE
J 0
(-6875 1950);
DISPLAY 0.893617 (-6875 1950);
PAINT GREEN (-6875 1950);
DISPLAY INVISIBLE (-6875 1950);
FORCEPROP 1 LAST COMMENT_BODY TRUE
J 0
(-7075 1975);
DISPLAY 0.893617 (-7075 1975);
PAINT GREEN (-7075 1975);
DISPLAY INVISIBLE (-7075 1975);
FORCEADD OFFPAGE..1
(-7225 1600);
FORCEPROP 2 LAST $XR0 201 
J 0
(-7477 1600);
DISPLAY 0.638298 (-7477 1600);
PAINT MONO (-7477 1600);
FORCEPROP 1 LAST OFFPAGE TRUE
J 0
(-6900 1475);
DISPLAY 0.893617 (-6900 1475);
PAINT GREEN (-6900 1475);
DISPLAY INVISIBLE (-6900 1475);
FORCEPROP 1 LAST COMMENT_BODY TRUE
J 0
(-7100 1500);
DISPLAY 0.893617 (-7100 1500);
PAINT GREEN (-7100 1500);
DISPLAY INVISIBLE (-7100 1500);
FORCEPROP 2 LAST PATH I41
J 0
(-7160 1660);
DISPLAY 1.021277 (-7160 1660);
PAINT ORANGE (-7160 1660);
DISPLAY INVISIBLE (-7160 1660);
FORCEPROP 2 LAST CDS_LIB mstr_standard
J 0
(-7225 1600);
PAINT ORANGE (-7225 1600);
DISPLAY INVISIBLE (-7225 1600);
FORCEPROP 2 LAST BOM_COST PROC_VRD_VCCIN_CPU0
J 0
(-7425 1650);
PAINT MONO (-7425 1650);
DISPLAY INVISIBLE (-7425 1650);
FORCEPROP 2 LAST ROOM PVSA_CPU0_VSENSE_VR
J 0
(-7750 1675);
PAINT ORANGE (-7750 1675);
DISPLAY INVISIBLE (-7750 1675);
FORCEADD P5V_STBY..1
(-4900 4650);
FORCEPROP 3 LASTPIN (-4900 4600) SIG_NAME P5V_STBY\g
J 0
(-4890 4610);
DISPLAY 0.659574 (-4890 4610);
PAINT MONO (-4890 4610);
DISPLAY INVISIBLE (-4890 4610);
FORCEPROP 1 LAST PATH I42
J 0
(-4855 4652);
DISPLAY 0.340426 (-4855 4652);
PAINT GREEN (-4855 4652);
DISPLAY INVISIBLE (-4855 4652);
FORCEPROP 2 LAST CDS_LIB mstr_symbols
J 0
(-4900 4650);
PAINT ORANGE (-4900 4650);
DISPLAY INVISIBLE (-4900 4650);
FORCEPROP 1 LAST SIZE 1B
J 0
(-4855 4672);
DISPLAY 0.340426 (-4855 4672);
PAINT GREEN (-4855 4672);
DISPLAY INVISIBLE (-4855 4672);
FORCEPROP 1 LAST BODY_TYPE PLUMBING
J 0
(-4945 4607);
DISPLAY 0.340426 (-4945 4607);
PAINT GREEN (-4945 4607);
DISPLAY INVISIBLE (-4945 4607);
FORCEPROP 1 LAST VOLTAGE 5.0V
J 0
(-4945 4607);
DISPLAY 0.340426 (-4945 4607);
PAINT SKYBLUE (-4945 4607);
DISPLAY INVISIBLE (-4945 4607);
FORCEPROP 1 LAST HDL_POWER P5V_STBY
J 0
(-5200 4525);
DISPLAY 0.872340 (-5200 4525);
PAINT ORANGE (-5200 4525);
DISPLAY INVISIBLE (-5200 4525);
FORCEADD CAP_A..1
(-950 2875);
FORCEPROP 1 LAST LOCATION C4C11
J 0
(-900 2975);
DISPLAY 0.617021 (-900 2975);
PAINT AQUA (-900 2975);
FORCEPROP 1 LAST PART_NUMBER E15431-004
J 0
(-900 2725);
DISPLAY 0.617021 (-900 2725);
PAINT BLUE (-900 2725);
FORCEPROP 1 LAST VALUE 22.0UF
J 0
(-900 2925);
DISPLAY 0.617021 (-900 2925);
PAINT SKYBLUE (-900 2925);
FORCEPROP 1 LAST PACK_TYPE 0603V
J 0
(-900 2675);
DISPLAY 0.617021 (-900 2675);
PAINT SKYBLUE (-900 2675);
FORCEPROP 1 LASTPIN (-950 2975) $PN 1
J 0
(-940 2955);
DISPLAY 0.617021 (-940 2955);
PAINT ORANGE (-940 2955);
FORCEPROP 1 LAST VOLTAGE 4V
J 0
(-900 2875);
DISPLAY 0.617021 (-900 2875);
PAINT SKYBLUE (-900 2875);
FORCEPROP 1 LAST TOLERANCE 20%
J 0
(-900 2825);
DISPLAY 0.617021 (-900 2825);
PAINT SKYBLUE (-900 2825);
FORCEPROP 1 LAST MATERIAL X6S
J 0
(-900 2775);
DISPLAY 0.617021 (-900 2775);
PAINT SKYBLUE (-900 2775);
FORCEPROP 1 LASTPIN (-950 2775) $PN 2
J 0
(-940 2755);
DISPLAY 0.617021 (-940 2755);
PAINT ORANGE (-940 2755);
FORCEPROP 2 LAST SEC 1
J 0
(-900 3075);
DISPLAY 0.680851 (-900 3075);
PAINT MONO (-900 3075);
DISPLAY INVISIBLE (-900 3075);
FORCEPROP 2 LAST SEC_TYPE 0603V
J 0
(-900 3075);
DISPLAY 1.021277 (-900 3075);
PAINT ORANGE (-900 3075);
DISPLAY INVISIBLE (-900 3075);
FORCEPROP 1 LAST PATH I43
J 0
(-900 3025);
DISPLAY 0.978723 (-900 3025);
PAINT WHITE (-900 3025);
DISPLAY INVISIBLE (-900 3025);
FORCEPROP 2 LAST CDS_SEC 1
J 0
(-900 3025);
PAINT ORANGE (-900 3025);
DISPLAY INVISIBLE (-900 3025);
FORCEPROP 2 LAST CDS_LIB dev_discrete
J 0
(-950 2875);
PAINT ORANGE (-950 2875);
DISPLAY INVISIBLE (-950 2875);
FORCEPROP 2 LAST CDS_LOCATION C4C11
J 0
(-900 2975);
DISPLAY 0.617021 (-900 2975);
PAINT AQUA (-900 2975);
DISPLAY INVISIBLE (-900 2975);
FORCEADD RES..2
(-625 2875);
FORCEPROP 1 LAST LOCATION R6N4
J 0
(-580 3000);
DISPLAY 0.617021 (-580 3000);
PAINT AQUA (-580 3000);
FORCEPROP 1 LAST PART_NUMBER G21796-208
J 0
(-585 2750);
DISPLAY 0.617021 (-585 2750);
PAINT BLUE (-585 2750);
FORCEPROP 1 LAST VALUE 51.1
J 0
(-580 2950);
DISPLAY 0.617021 (-580 2950);
PAINT SKYBLUE (-580 2950);
FORCEPROP 1 LAST TOLERANCE 1.0%
J 0
(-580 2900);
DISPLAY 0.617021 (-580 2900);
PAINT SKYBLUE (-580 2900);
FORCEPROP 1 LAST PACK_TYPE 0402
J 0
(-585 2700);
DISPLAY 0.617021 (-585 2700);
PAINT SKYBLUE (-585 2700);
FORCEPROP 1 LAST MATERIAL CHIP
J 0
(-585 2800);
DISPLAY 0.617021 (-585 2800);
PAINT SKYBLUE (-585 2800);
FORCEPROP 1 LAST WATTAGE 1/16W
J 0
(-585 2850);
DISPLAY 0.617021 (-585 2850);
PAINT SKYBLUE (-585 2850);
FORCEPROP 2 LAST CDS_SEC 1
J 0
(-575 3100);
DISPLAY 1.021277 (-575 3100);
PAINT ORANGE (-575 3100);
DISPLAY INVISIBLE (-575 3100);
FORCEPROP 2 LAST $SEC 1
J 0
(-575 3100);
DISPLAY 0.680851 (-575 3100);
PAINT MONO (-575 3100);
DISPLAY INVISIBLE (-575 3100);
FORCEPROP 1 LAST PATH I45
J 0
(-575 3050);
DISPLAY 0.978723 (-575 3050);
PAINT WHITE (-575 3050);
DISPLAY INVISIBLE (-575 3050);
FORCEPROP 2 LAST CDS_LIB mstr_discrete
J 0
(-625 2875);
PAINT ORANGE (-625 2875);
DISPLAY INVISIBLE (-625 2875);
FORCEPROP 2 LAST CDS_LOCATION R6N4
J 0
(-580 3000);
DISPLAY 0.617021 (-580 3000);
PAINT AQUA (-580 3000);
DISPLAY INVISIBLE (-580 3000);
FORCEPROP 1 LASTPIN (-625 2975) $PN 1
J 0
(-620 2937);
DISPLAY 0.787234 (-620 2937);
PAINT ORANGE (-620 2937);
DISPLAY INVISIBLE (-620 2937);
FORCEPROP 1 LASTPIN (-625 2775) $PN 2
J 0
(-620 2785);
DISPLAY 0.787234 (-620 2785);
PAINT ORANGE (-620 2785);
DISPLAY INVISIBLE (-620 2785);
FORCEADD IR354XX..1
(-3500 3725);
FORCEPROP 2 LASTPIN (-3000 3325) $PN 2
J 0
(-2990 3335);
DISPLAY 0.617021 (-2990 3335);
PAINT MONO (-2990 3335);
FORCEPROP 2 LASTPIN (-3000 4275) $PN 38
J 0
(-2990 4285);
DISPLAY 0.617021 (-2990 4285);
PAINT MONO (-2990 4285);
FORCEPROP 1 LAST VALUE IR35412
J 1
(-3500 4350);
DISPLAY 0.617021 (-3500 4350);
PAINT SKYBLUE (-3500 4350);
FORCEPROP 1 LAST LOCATION EU4C1
J 0
(-3950 4525);
DISPLAY 0.617021 (-3950 4525);
PAINT AQUA (-3950 4525);
FORCEPROP 1 LAST MATERIAL IC
J 0
(-3950 4475);
DISPLAY 0.617021 (-3950 4475);
PAINT SKYBLUE (-3950 4475);
FORCEPROP 2 LASTPIN (-4000 4225) $PN 30
J 2
(-4010 4235);
DISPLAY 0.617021 (-4010 4235);
PAINT MONO (-4010 4235);
FORCEPROP 2 LASTPIN (-4000 4175) $PN 25
J 2
(-4010 4185);
DISPLAY 0.617021 (-4010 4185);
PAINT MONO (-4010 4185);
FORCEPROP 2 LASTPIN (-4000 4275) $PN 3
J 2
(-4010 4285);
DISPLAY 0.617021 (-4010 4285);
PAINT MONO (-4010 4285);
FORCEPROP 2 LASTPIN (-4000 4075) $PN 4
J 2
(-4010 4085);
DISPLAY 0.617021 (-4010 4085);
PAINT MONO (-4010 4085);
FORCEPROP 2 LASTPIN (-3000 4075) $PN 37
J 0
(-2990 4085);
DISPLAY 0.617021 (-2990 4085);
PAINT MONO (-2990 4085);
FORCEPROP 2 LASTPIN (-3000 3775) $PN 36
J 0
(-2990 3785);
DISPLAY 0.617021 (-2990 3785);
PAINT MONO (-2990 3785);
FORCEPROP 2 LASTPIN (-3000 4025) $PN 31
J 0
(-2990 4035);
DISPLAY 0.617021 (-2990 4035);
PAINT MONO (-2990 4035);
FORCEPROP 2 LASTPIN (-3000 3425) $PN 10
J 0
(-2990 3435);
DISPLAY 0.617021 (-2990 3435);
PAINT MONO (-2990 3435);
FORCEPROP 2 LASTPIN (-3000 3275) $PN 40
J 0
(-2990 3285);
DISPLAY 0.617021 (-2990 3285);
PAINT MONO (-2990 3285);
FORCEPROP 2 LASTPIN (-3000 3225) $PN 7
J 0
(-2990 3235);
DISPLAY 0.617021 (-2990 3235);
PAINT MONO (-2990 3235);
FORCEPROP 2 LASTPIN (-3000 3175) $PN 5
J 0
(-2990 3185);
DISPLAY 0.617021 (-2990 3185);
PAINT MONO (-2990 3185);
FORCEPROP 2 LASTPIN (-4000 3975) $PN 35
J 2
(-4010 3985);
DISPLAY 0.617021 (-4010 3985);
PAINT MONO (-4010 3985);
FORCEPROP 2 LASTPIN (-4000 3875) $PN 1
J 2
(-4010 3885);
DISPLAY 0.617021 (-4010 3885);
PAINT MONO (-4010 3885);
FORCEPROP 2 LASTPIN (-4000 3725) $PN 6
J 2
(-4010 3735);
DISPLAY 0.617021 (-4010 3735);
PAINT MONO (-4010 3735);
FORCEPROP 2 LASTPIN (-4000 3775) $PN 41
J 2
(-4010 3785);
DISPLAY 0.617021 (-4010 3785);
PAINT MONO (-4010 3785);
FORCEPROP 2 LASTPIN (-4000 3625) $PN 34
J 2
(-4010 3635);
DISPLAY 0.617021 (-4010 3635);
PAINT MONO (-4010 3635);
FORCEPROP 2 LASTPIN (-4000 3525) $PN 39
J 2
(-4010 3535);
DISPLAY 0.617021 (-4010 3535);
PAINT MONO (-4010 3535);
FORCEPROP 2 LASTPIN (-4000 3425) $PN 33
J 2
(-4010 3435);
DISPLAY 0.617021 (-4010 3435);
PAINT MONO (-4010 3435);
FORCEPROP 1 LAST PART_NUMBER H73684-001
J 0
(-3950 3025);
DISPLAY 0.617021 (-3950 3025);
PAINT BLUE (-3950 3025);
FORCEPROP 2 LASTPIN (-4000 3375) $PN 32
J 2
(-4010 3385);
DISPLAY 0.617021 (-4010 3385);
PAINT MONO (-4010 3385);
FORCEPROP 1 LAST PATH I46
J 0
(-3500 4475);
PAINT GREEN (-3500 4475);
DISPLAY INVISIBLE (-3500 4475);
FORCEPROP 1 LAST PACK_TYPE SM
J 0
(-3950 4575);
PAINT SKYBLUE (-3950 4575);
DISPLAY INVISIBLE (-3950 4575);
FORCEPROP 2 LAST $SEC 1
J 0
(-3950 4575);
PAINT MONO (-3950 4575);
DISPLAY INVISIBLE (-3950 4575);
FORCEPROP 2 LAST CDS_SEC 1
J 0
(-3950 4575);
PAINT MONO (-3950 4575);
DISPLAY INVISIBLE (-3950 4575);
FORCEPROP 2 LAST CDS_LOCATION EU4C1
J 0
(-3950 4525);
PAINT GREEN (-3950 4525);
DISPLAY INVISIBLE (-3950 4525);
FORCEPROP 2 LAST CDS_LIB mstr_discrete
J 0
(-3500 3725);
PAINT ORANGE (-3500 3725);
DISPLAY INVISIBLE (-3500 3725);
FORCEADD CAP_A..1
(-1300 2875);
FORCEPROP 1 LAST PART_NUMBER E15431-004
J 0
(-1250 2725);
DISPLAY 0.617021 (-1250 2725);
PAINT BLUE (-1250 2725);
FORCEPROP 1 LAST PACK_TYPE 0603V
J 0
(-1250 2675);
DISPLAY 0.617021 (-1250 2675);
PAINT SKYBLUE (-1250 2675);
FORCEPROP 1 LAST TOLERANCE 20%
J 0
(-1250 2825);
DISPLAY 0.617021 (-1250 2825);
PAINT SKYBLUE (-1250 2825);
FORCEPROP 1 LAST VALUE 22.0UF
J 0
(-1250 2925);
DISPLAY 0.617021 (-1250 2925);
PAINT SKYBLUE (-1250 2925);
FORCEPROP 1 LAST LOCATION C6N7
J 0
(-1250 2975);
DISPLAY 0.617021 (-1250 2975);
PAINT AQUA (-1250 2975);
FORCEPROP 1 LAST VOLTAGE 4V
J 0
(-1250 2875);
DISPLAY 0.617021 (-1250 2875);
PAINT SKYBLUE (-1250 2875);
FORCEPROP 1 LAST MATERIAL X6S
J 0
(-1250 2775);
DISPLAY 0.617021 (-1250 2775);
PAINT SKYBLUE (-1250 2775);
FORCEPROP 1 LASTPIN (-1300 2975) $PN 1
J 0
(-1290 2955);
DISPLAY 0.617021 (-1290 2955);
PAINT ORANGE (-1290 2955);
FORCEPROP 1 LASTPIN (-1300 2775) $PN 2
J 0
(-1290 2755);
DISPLAY 0.617021 (-1290 2755);
PAINT ORANGE (-1290 2755);
FORCEPROP 2 LAST SEC 1
J 0
(-1245 3075);
DISPLAY 0.680851 (-1245 3075);
PAINT MONO (-1245 3075);
DISPLAY INVISIBLE (-1245 3075);
FORCEPROP 2 LAST SEC_TYPE 0603V
J 0
(-1245 3075);
DISPLAY 1.021277 (-1245 3075);
PAINT ORANGE (-1245 3075);
DISPLAY INVISIBLE (-1245 3075);
FORCEPROP 2 LAST BOM_COST PROC_VRD_VCCIN_CPU0
J 0
(-1250 3025);
DISPLAY 1.446809 (-1250 3025);
PAINT MONO (-1250 3025);
DISPLAY INVISIBLE (-1250 3025);
FORCEPROP 2 LAST ROOM PVSA_CPU0_PWR_VR
J 0
(-1250 3025);
DISPLAY 1.446809 (-1250 3025);
PAINT MONO (-1250 3025);
DISPLAY INVISIBLE (-1250 3025);
FORCEPROP 1 LAST PATH I5
J 0
(-1250 3025);
DISPLAY 0.978723 (-1250 3025);
PAINT WHITE (-1250 3025);
DISPLAY INVISIBLE (-1250 3025);
FORCEPROP 2 LAST CDS_SEC 1
J 0
(-1250 3025);
PAINT ORANGE (-1250 3025);
DISPLAY INVISIBLE (-1250 3025);
FORCEPROP 2 LAST CDS_LOCATION C6N7
J 0
(-1250 2975);
DISPLAY 0.617021 (-1250 2975);
PAINT AQUA (-1250 2975);
DISPLAY INVISIBLE (-1250 2975);
FORCEPROP 2 LAST CDS_LIB dev_discrete
J 0
(-1300 2875);
PAINT ORANGE (-1300 2875);
DISPLAY INVISIBLE (-1300 2875);
FORCEADD GND..1
(-625 2525);
FORCEPROP 3 LASTPIN (-625 2575) SIG_NAME GND\g
J 0
(-615 2585);
DISPLAY 0.659574 (-615 2585);
PAINT MONO (-615 2585);
DISPLAY INVISIBLE (-615 2585);
FORCEPROP 1 LAST HDL_POWER GND
J 0
(-625 2675);
DISPLAY 1.723404 (-625 2675);
PAINT GREEN (-625 2675);
DISPLAY INVISIBLE (-625 2675);
FORCEPROP 2 LAST BOM_COST PROC_VRD_VCCIN_CPU0
J 0
(-1000 2600);
DISPLAY 1.446809 (-1000 2600);
PAINT MONO (-1000 2600);
DISPLAY INVISIBLE (-1000 2600);
FORCEPROP 1 LAST VOLTAGE 0
J 0
(-625 2525);
PAINT SKYBLUE (-625 2525);
DISPLAY INVISIBLE (-625 2525);
FORCEPROP 2 LAST CDS_LIB mstr_symbols
J 0
(-625 2525);
PAINT ORANGE (-625 2525);
DISPLAY INVISIBLE (-625 2525);
FORCEPROP 1 LAST PATH I6
J 0
(-550 2525);
DISPLAY 0.872340 (-550 2525);
PAINT AQUA (-550 2525);
DISPLAY INVISIBLE (-550 2525);
FORCEPROP 1 LAST SIZE 1B
J 0
(-550 2475);
DISPLAY 1.723404 (-550 2475);
PAINT GREEN (-550 2475);
DISPLAY INVISIBLE (-550 2475);
FORCEPROP 1 LAST BODY_TYPE PLUMBING
J 0
(-670 2482);
DISPLAY 0.340426 (-670 2482);
PAINT GREEN (-670 2482);
DISPLAY INVISIBLE (-670 2482);
FORCEPROP 2 LAST ROOM PVSA_CPU0_PWR_VR
J 0
(-1175 2600);
DISPLAY 1.936170 (-1175 2600);
PAINT ORANGE (-1175 2600);
DISPLAY INVISIBLE (-1175 2600);
FORCEADD RES..2
(-1125 3900);
FORCEPROP 1 LAST MATERIAL EMPTY
J 0
(-1085 3825);
DISPLAY 0.617021 (-1085 3825);
PAINT RED (-1085 3825);
FORCEPROP 1 LAST LOCATION R4C13
J 0
(-1080 4025);
DISPLAY 0.617021 (-1080 4025);
PAINT AQUA (-1080 4025);
FORCEPROP 1 LAST PART_NUMBER G21796-187
J 0
(-1085 3775);
DISPLAY 0.617021 (-1085 3775);
PAINT BLUE (-1085 3775);
FORCEPROP 1 LAST VALUE 68.1K
J 0
(-1080 3975);
DISPLAY 0.617021 (-1080 3975);
PAINT SKYBLUE (-1080 3975);
FORCEPROP 1 LAST TOLERANCE 1%
J 0
(-1080 3925);
DISPLAY 0.617021 (-1080 3925);
PAINT SKYBLUE (-1080 3925);
FORCEPROP 1 LAST PACK_TYPE 0402
J 0
(-1085 3725);
DISPLAY 0.617021 (-1085 3725);
PAINT SKYBLUE (-1085 3725);
FORCEPROP 1 LAST WATTAGE 1/16W
J 0
(-1085 3875);
DISPLAY 0.617021 (-1085 3875);
PAINT SKYBLUE (-1085 3875);
FORCEPROP 1 LASTPIN (-1125 4000) $PN 1
J 0
(-1120 3962);
DISPLAY 0.617021 (-1120 3962);
PAINT ORANGE (-1120 3962);
FORCEPROP 1 LASTPIN (-1125 3800) $PN 2
J 0
(-1120 3810);
DISPLAY 0.617021 (-1120 3810);
PAINT ORANGE (-1120 3810);
FORCEPROP 2 LAST $SEC 1
J 0
(-1075 4125);
PAINT MONO (-1075 4125);
DISPLAY INVISIBLE (-1075 4125);
FORCEPROP 2 LAST CDS_SEC 1
J 0
(-1075 4125);
PAINT MONO (-1075 4125);
DISPLAY INVISIBLE (-1075 4125);
FORCEPROP 1 LAST PATH I62
J 0
(-1075 4075);
DISPLAY 0.978723 (-1075 4075);
PAINT WHITE (-1075 4075);
DISPLAY INVISIBLE (-1075 4075);
FORCEPROP 2 LAST CDS_LIB mstr_discrete
J 0
(-1125 3900);
PAINT ORANGE (-1125 3900);
DISPLAY INVISIBLE (-1125 3900);
FORCEADD GND..1
(-1125 3625);
FORCEPROP 3 LASTPIN (-1125 3675) SIG_NAME GND\g
J 0
(-1115 3685);
DISPLAY 0.659574 (-1115 3685);
PAINT MONO (-1115 3685);
DISPLAY INVISIBLE (-1115 3685);
FORCEPROP 1 LAST HDL_POWER GND
J 0
(-1125 3775);
DISPLAY 1.723404 (-1125 3775);
PAINT GREEN (-1125 3775);
DISPLAY INVISIBLE (-1125 3775);
FORCEPROP 1 LAST VOLTAGE 0
J 0
(-1125 3625);
PAINT SKYBLUE (-1125 3625);
DISPLAY INVISIBLE (-1125 3625);
FORCEPROP 2 LAST CDS_LIB mstr_symbols
J 0
(-1125 3625);
PAINT ORANGE (-1125 3625);
DISPLAY INVISIBLE (-1125 3625);
FORCEPROP 1 LAST PATH I63
J 0
(-1050 3625);
DISPLAY 0.872340 (-1050 3625);
PAINT AQUA (-1050 3625);
DISPLAY INVISIBLE (-1050 3625);
FORCEPROP 2 LAST BOM_COST PROC_VRD_VCCIN_CPU0
J 0
(-1500 3700);
DISPLAY 1.446809 (-1500 3700);
PAINT MONO (-1500 3700);
DISPLAY INVISIBLE (-1500 3700);
FORCEPROP 1 LAST SIZE 1B
J 0
(-1050 3575);
DISPLAY 1.723404 (-1050 3575);
PAINT GREEN (-1050 3575);
DISPLAY INVISIBLE (-1050 3575);
FORCEPROP 1 LAST BODY_TYPE PLUMBING
J 0
(-1170 3582);
DISPLAY 0.340426 (-1170 3582);
PAINT GREEN (-1170 3582);
DISPLAY INVISIBLE (-1170 3582);
FORCEPROP 2 LAST ROOM PVSA_CPU1_PWR_VR
J 0
(-1675 3700);
DISPLAY 1.936170 (-1675 3700);
PAINT ORANGE (-1675 3700);
DISPLAY INVISIBLE (-1675 3700);
FORCEADD SC2K2P50V3KX-GP..1
(-2225 3250);
FORCEPROP 1 LAST VALUE SC2K2P50V3KX-GP
J 0
(-2200 3200);
DISPLAY 0.617021 (-2200 3200);
PAINT GREEN (-2200 3200);
FORCEPROP 0 LAST STATUS NOPOP
J 0
(-2175 3325);
DISPLAY 1.021277 (-2175 3325);
PAINT ORANGE (-2175 3325);
FORCEPROP 1 LAST LOCATION CT59
J 0
(-2200 3280);
DISPLAY 0.617021 (-2200 3280);
PAINT GREEN (-2200 3280);
FORCEPROP 1 LAST PACK_TYPE SMD-BCG6
J 0
(-2225 3250);
DISPLAY 0.617021 (-2225 3250);
PAINT GREEN (-2225 3250);
DISPLAY INVISIBLE (-2225 3250);
FORCEPROP 1 LAST PART_NUMBER 78.22224.2BL
J 0
(-2225 3250);
DISPLAY 0.617021 (-2225 3250);
PAINT GREEN (-2225 3250);
DISPLAY INVISIBLE (-2225 3250);
FORCEPROP 1 LAST PATH I64
J 0
(-2225 3250);
DISPLAY 0.617021 (-2225 3250);
PAINT GREEN (-2225 3250);
DISPLAY INVISIBLE (-2225 3250);
FORCEPROP 2 LAST CDS_LIB w_hdl
J 0
(-2225 3250);
PAINT MONO (-2225 3250);
DISPLAY INVISIBLE (-2225 3250);
FORCEPROP 1 LAST CDS_LMAN_SYM_OUTLINE -50,25,50,-25
J 0
(-2225 3250);
DISPLAY 0.468085 (-2225 3250);
PAINT GREEN (-2225 3250);
DISPLAY INVISIBLE (-2225 3250);
FORCEADD CAP..1
(-2375 3750);
FORCEPROP 1 LAST MATERIAL X7R
J 0
(-2325 3650);
DISPLAY 0.617021 (-2325 3650);
PAINT SKYBLUE (-2325 3650);
FORCEPROP 1 LAST TOLERANCE 10%
J 0
(-2325 3700);
DISPLAY 0.617021 (-2325 3700);
PAINT SKYBLUE (-2325 3700);
FORCEPROP 1 LAST PACK_TYPE 0402LF
J 0
(-2325 3550);
DISPLAY 0.617021 (-2325 3550);
PAINT SKYBLUE (-2325 3550);
FORCEPROP 1 LAST PART_NUMBER A36096-046
J 0
(-2325 3600);
DISPLAY 0.617021 (-2325 3600);
PAINT BLUE (-2325 3600);
FORCEPROP 0 LAST STATUS NOPOP
J 0
(-2350 3825);
DISPLAY 1.021277 (-2350 3825);
PAINT ORANGE (-2350 3825);
FORCEPROP 1 LAST VALUE 1000PF
J 0
(-2325 3800);
DISPLAY 0.617021 (-2325 3800);
PAINT SKYBLUE (-2325 3800);
FORCEPROP 1 LAST VOLTAGE 50V
J 0
(-2325 3750);
DISPLAY 0.617021 (-2325 3750);
PAINT SKYBLUE (-2325 3750);
FORCEPROP 1 LAST LOCATION CT58
J 0
(-2525 3750);
DISPLAY 0.617021 (-2525 3750);
PAINT AQUA (-2525 3750);
FORCEPROP 1 LASTPIN (-2375 3850) $PN 1
J 0
(-2365 3830);
DISPLAY 0.787234 (-2365 3830);
PAINT ORANGE (-2365 3830);
DISPLAY INVISIBLE (-2365 3830);
FORCEPROP 1 LASTPIN (-2375 3650) $PN 2
J 0
(-2365 3630);
DISPLAY 0.787234 (-2365 3630);
PAINT ORANGE (-2365 3630);
DISPLAY INVISIBLE (-2365 3630);
FORCEPROP 2 LAST CDS_LIB mstr_discrete
J 0
(-2375 3750);
PAINT MONO (-2375 3750);
DISPLAY INVISIBLE (-2375 3750);
FORCEPROP 1 LAST PATH I65
J 0
(-2325 3900);
DISPLAY 0.978723 (-2325 3900);
PAINT WHITE (-2325 3900);
DISPLAY INVISIBLE (-2325 3900);
FORCEPROP 0 LAST ROOM VDDQ_KLM_PWR_VR
J 0
(-2325 3950);
DISPLAY 1.021277 (-2325 3950);
PAINT ORANGE (-2325 3950);
DISPLAY INVISIBLE (-2325 3950);
FORCEADD GND..1
(-2375 3550);
FORCEPROP 3 LASTPIN (-2375 3600) SIG_NAME GND\g
J 0
(-2365 3610);
DISPLAY 0.659574 (-2365 3610);
PAINT MONO (-2365 3610);
DISPLAY INVISIBLE (-2365 3610);
FORCEPROP 2 LAST CDS_LIB mstr_symbols
J 0
(-2375 3550);
PAINT MONO (-2375 3550);
DISPLAY INVISIBLE (-2375 3550);
FORCEPROP 1 LAST PATH I66
J 0
(-2300 3550);
DISPLAY 0.872340 (-2300 3550);
PAINT AQUA (-2300 3550);
DISPLAY INVISIBLE (-2300 3550);
FORCEPROP 1 LAST HDL_POWER GND
J 0
(-2375 3700);
DISPLAY 1.170213 (-2375 3700);
PAINT GREEN (-2375 3700);
DISPLAY INVISIBLE (-2375 3700);
FORCEPROP 1 LAST SIZE 1B
J 0
(-2300 3500);
DISPLAY 1.170213 (-2300 3500);
PAINT AQUA (-2300 3500);
DISPLAY INVISIBLE (-2300 3500);
FORCEPROP 1 LAST BODY_TYPE PLUMBING
J 0
(-2420 3507);
DISPLAY 0.340426 (-2420 3507);
PAINT GREEN (-2420 3507);
DISPLAY INVISIBLE (-2420 3507);
FORCEPROP 1 LAST VOLTAGE 0
J 0
(-2375 3550);
PAINT SKYBLUE (-2375 3550);
DISPLAY INVISIBLE (-2375 3550);
FORCEPROP 2 LAST ROOM VDDQ_KLM_PWR_VR
J 0
(-2950 3625);
DISPLAY 1.361702 (-2950 3625);
PAINT ORANGE (-2950 3625);
DISPLAY INVISIBLE (-2950 3625);
FORCEADD GND..1
(-2225 2750);
FORCEPROP 3 LASTPIN (-2225 2800) SIG_NAME GND\g
J 0
(-2215 2810);
DISPLAY 0.659574 (-2215 2810);
PAINT MONO (-2215 2810);
DISPLAY INVISIBLE (-2215 2810);
FORCEPROP 2 LAST ROOM PVCCIN_CPU0_PWR_VR
J 0
(-2775 2825);
DISPLAY 1.936170 (-2775 2825);
PAINT ORANGE (-2775 2825);
DISPLAY INVISIBLE (-2775 2825);
FORCEPROP 2 LAST BOM_COST PROC_VRD_VCCIN_CPU0
J 0
(-2600 2825);
DISPLAY 1.446809 (-2600 2825);
PAINT MONO (-2600 2825);
DISPLAY INVISIBLE (-2600 2825);
FORCEPROP 1 LAST BODY_TYPE PLUMBING
J 0
(-2270 2707);
DISPLAY 0.340426 (-2270 2707);
PAINT GREEN (-2270 2707);
DISPLAY INVISIBLE (-2270 2707);
FORCEPROP 1 LAST VOLTAGE 0
J 0
(-2225 2750);
PAINT SKYBLUE (-2225 2750);
DISPLAY INVISIBLE (-2225 2750);
FORCEPROP 1 LAST SIZE 1B
J 0
(-2150 2700);
DISPLAY 1.723404 (-2150 2700);
PAINT GREEN (-2150 2700);
DISPLAY INVISIBLE (-2150 2700);
FORCEPROP 1 LAST HDL_POWER GND
J 0
(-2225 2900);
DISPLAY 1.723404 (-2225 2900);
PAINT GREEN (-2225 2900);
DISPLAY INVISIBLE (-2225 2900);
FORCEPROP 1 LAST PATH I67
J 0
(-2150 2750);
DISPLAY 0.872340 (-2150 2750);
PAINT AQUA (-2150 2750);
DISPLAY INVISIBLE (-2150 2750);
FORCEPROP 2 LAST CDS_LIB mstr_symbols
J 0
(-2225 2750);
PAINT MONO (-2225 2750);
DISPLAY INVISIBLE (-2225 2750);
FORCEADD 3D01R5F-GP..1
R 4
(-2225 2950);
FORCEPROP 1 LAST VALUE 3D01R5F-GP
J 0
(-2175 2975);
DISPLAY 0.617021 (-2175 2975);
PAINT GREEN (-2175 2975);
FORCEPROP 0 LAST STATUS NOPOP
J 0
(-2200 3050);
DISPLAY 1.021277 (-2200 3050);
PAINT ORANGE (-2200 3050);
FORCEPROP 1 LAST LOCATION RT39
J 0
(-2175 3020);
DISPLAY 0.617021 (-2175 3020);
PAINT GREEN (-2175 3020);
FORCEPROP 2 LASTPIN (-2225 3075) SIG_NAME UN$205$3D01R5F-GP$I68$2
J 0
(-2215 3085);
DISPLAY 0.659574 (-2215 3085);
PAINT MONO (-2215 3085);
DISPLAY INVISIBLE (-2215 3085);
FORCEPROP 1 LAST PACK_TYPE SMD-RG5
R 2
J 0
(-2225 2950);
DISPLAY 0.617021 (-2225 2950);
PAINT GREEN (-2225 2950);
DISPLAY INVISIBLE (-2225 2950);
FORCEPROP 1 LAST PART_NUMBER 64.3R015.16L
R 2
J 0
(-2225 2950);
DISPLAY 0.617021 (-2225 2950);
PAINT GREEN (-2225 2950);
DISPLAY INVISIBLE (-2225 2950);
FORCEPROP 2 LAST CDS_LIB w_hdl
J 0
(-2225 2950);
PAINT MONO (-2225 2950);
DISPLAY INVISIBLE (-2225 2950);
FORCEPROP 1 LAST PATH I68
R 2
J 0
(-2225 2950);
DISPLAY 0.617021 (-2225 2950);
PAINT GREEN (-2225 2950);
DISPLAY INVISIBLE (-2225 2950);
FORCEPROP 1 LAST CDS_LMAN_SYM_OUTLINE -50,75,50,-75
R 2
J 0
(-2225 2950);
DISPLAY 0.468085 (-2225 2950);
PAINT GREEN (-2225 2950);
DISPLAY INVISIBLE (-2225 2950);
FORCEADD CAP_A..1
(-4200 3225);
FORCEPROP 1 LAST TOLERANCE 10%
J 0
(-4150 3175);
DISPLAY 0.617021 (-4150 3175);
PAINT SKYBLUE (-4150 3175);
FORCEPROP 1 LAST PACK_TYPE 0402V
J 0
(-4150 3025);
DISPLAY 0.617021 (-4150 3025);
PAINT SKYBLUE (-4150 3025);
FORCEPROP 1 LAST PART_NUMBER A36096-030
J 0
(-4150 3075);
DISPLAY 0.617021 (-4150 3075);
PAINT BLUE (-4150 3075);
FORCEPROP 1 LAST MATERIAL X7R
J 0
(-4150 3125);
DISPLAY 0.617021 (-4150 3125);
PAINT SKYBLUE (-4150 3125);
FORCEPROP 1 LAST LOCATION CT60
J 0
(-4350 3225);
DISPLAY 0.617021 (-4350 3225);
PAINT AQUA (-4350 3225);
FORCEPROP 1 LAST VOLTAGE 16V
J 0
(-4150 3225);
DISPLAY 0.617021 (-4150 3225);
PAINT SKYBLUE (-4150 3225);
FORCEPROP 1 LAST VALUE 0.1UF
J 0
(-4150 3275);
DISPLAY 0.617021 (-4150 3275);
PAINT SKYBLUE (-4150 3275);
FORCEPROP 0 LAST STATUS NOPOP
J 0
(-4475 3150);
DISPLAY 1.021277 (-4475 3150);
PAINT ORANGE (-4475 3150);
FORCEPROP 1 LASTPIN (-4200 3125) $PN 2
J 0
(-4190 3105);
DISPLAY 0.787234 (-4190 3105);
PAINT ORANGE (-4190 3105);
DISPLAY INVISIBLE (-4190 3105);
FORCEPROP 1 LASTPIN (-4200 3325) $PN 1
J 0
(-4190 3305);
DISPLAY 0.787234 (-4190 3305);
PAINT ORANGE (-4190 3305);
DISPLAY INVISIBLE (-4190 3305);
FORCEPROP 2 LAST ROOM PVCCIN_CPU0_PWR_VR
J 0
(-4150 3375);
DISPLAY 1.361702 (-4150 3375);
PAINT ORANGE (-4150 3375);
DISPLAY INVISIBLE (-4150 3375);
FORCEPROP 1 LAST PATH I69
J 0
(-4150 3375);
DISPLAY 0.978723 (-4150 3375);
PAINT WHITE (-4150 3375);
DISPLAY INVISIBLE (-4150 3375);
FORCEPROP 2 LAST CDS_LIB dev_discrete
J 0
(-4200 3225);
PAINT MONO (-4200 3225);
DISPLAY INVISIBLE (-4200 3225);
FORCEADD INDUCTOR..1
(-1725 3425);
FORCEPROP 1 LAST PACK_TYPE SM
J 0
(-1760 3290);
DISPLAY 0.617021 (-1760 3290);
PAINT SKYBLUE (-1760 3290);
FORCEPROP 1 LAST MATERIAL IND
J 0
(-1710 3340);
DISPLAY 0.617021 (-1710 3340);
PAINT SKYBLUE (-1710 3340);
FORCEPROP 1 LAST PART_NUMBER D92183-036
J 0
(-1825 3525);
DISPLAY 0.617021 (-1825 3525);
PAINT BLUE (-1825 3525);
FORCEPROP 1 LASTPIN (-1625 3425) $PN 2
J 2
(-1615 3435);
DISPLAY 0.617021 (-1615 3435);
PAINT WHITE (-1615 3435);
FORCEPROP 1 LAST LOCATION L4C2
J 0
(-1825 3475);
DISPLAY 0.617021 (-1825 3475);
PAINT AQUA (-1825 3475);
FORCEPROP 1 LASTPIN (-1825 3425) $PN 1
J 0
(-1825 3435);
DISPLAY 0.617021 (-1825 3435);
PAINT WHITE (-1825 3435);
FORCEPROP 1 LAST VALUE 0.3UH
J 2
(-1730 3340);
DISPLAY 0.617021 (-1730 3340);
PAINT SKYBLUE (-1730 3340);
FORCEPROP 2 LAST SEC_TYPE SM
J 0
(-1825 3625);
DISPLAY 1.021277 (-1825 3625);
PAINT ORANGE (-1825 3625);
DISPLAY INVISIBLE (-1825 3625);
FORCEPROP 2 LAST SEC 1
J 0
(-1825 3625);
DISPLAY 0.680851 (-1825 3625);
PAINT MONO (-1825 3625);
DISPLAY INVISIBLE (-1825 3625);
FORCEPROP 1 LAST PATH I7
J 0
(-1825 3575);
DISPLAY 0.978723 (-1825 3575);
PAINT ORANGE (-1825 3575);
DISPLAY INVISIBLE (-1825 3575);
FORCEPROP 2 LAST CDS_LIB mstr_discrete
J 0
(-1725 3425);
PAINT ORANGE (-1725 3425);
DISPLAY INVISIBLE (-1725 3425);
FORCEPROP 2 LAST CDS_LOCATION L4C2
J 0
(-1825 3475);
DISPLAY 0.617021 (-1825 3475);
PAINT AQUA (-1825 3475);
DISPLAY INVISIBLE (-1825 3475);
FORCEPROP 2 LAST ROOM PVSA_CPU0_PWR_VR
J 0
(-1825 3525);
DISPLAY 1.361702 (-1825 3525);
PAINT ORANGE (-1825 3525);
DISPLAY INVISIBLE (-1825 3525);
FORCEADD GND..1
(-4200 2975);
FORCEPROP 3 LASTPIN (-4200 3025) SIG_NAME GND\g
J 0
(-4190 3035);
DISPLAY 0.659574 (-4190 3035);
PAINT MONO (-4190 3035);
DISPLAY INVISIBLE (-4190 3035);
FORCEPROP 1 LAST BODY_TYPE PLUMBING
J 0
(-4245 2932);
DISPLAY 0.340426 (-4245 2932);
PAINT GREEN (-4245 2932);
DISPLAY INVISIBLE (-4245 2932);
FORCEPROP 2 LAST ROOM PVCCIN_CPU0_PWR_VR
J 0
(-4750 3050);
DISPLAY 1.936170 (-4750 3050);
PAINT ORANGE (-4750 3050);
DISPLAY INVISIBLE (-4750 3050);
FORCEPROP 2 LAST BOM_COST PROC_VRD_VCCIN_CPU0
J 0
(-4575 3050);
DISPLAY 1.446809 (-4575 3050);
PAINT MONO (-4575 3050);
DISPLAY INVISIBLE (-4575 3050);
FORCEPROP 1 LAST SIZE 1B
J 0
(-4125 2925);
DISPLAY 1.723404 (-4125 2925);
PAINT GREEN (-4125 2925);
DISPLAY INVISIBLE (-4125 2925);
FORCEPROP 1 LAST VOLTAGE 0
J 0
(-4200 2975);
PAINT SKYBLUE (-4200 2975);
DISPLAY INVISIBLE (-4200 2975);
FORCEPROP 1 LAST HDL_POWER GND
J 0
(-4200 3125);
DISPLAY 1.723404 (-4200 3125);
PAINT GREEN (-4200 3125);
DISPLAY INVISIBLE (-4200 3125);
FORCEPROP 1 LAST PATH I70
J 0
(-4125 2975);
DISPLAY 0.872340 (-4125 2975);
PAINT AQUA (-4125 2975);
DISPLAY INVISIBLE (-4125 2975);
FORCEPROP 2 LAST CDS_LIB mstr_symbols
J 0
(-4200 2975);
PAINT MONO (-4200 2975);
DISPLAY INVISIBLE (-4200 2975);
FORCEADD RES..1
(-5600 3500);
FORCEPROP 1 LAST WATTAGE 1/16W
J 2
(-5625 3350);
DISPLAY 0.617021 (-5625 3350);
PAINT SKYBLUE (-5625 3350);
FORCEPROP 1 LAST PACK_TYPE 0402
J 0
(-5500 3350);
DISPLAY 0.617021 (-5500 3350);
PAINT SKYBLUE (-5500 3350);
FORCEPROP 1 LAST MATERIAL CHIP
J 0
(-5600 3350);
DISPLAY 0.617021 (-5600 3350);
PAINT SKYBLUE (-5600 3350);
FORCEPROP 1 LAST TOLERANCE 5%
J 0
(-5600 3400);
DISPLAY 0.617021 (-5600 3400);
PAINT SKYBLUE (-5600 3400);
FORCEPROP 1 LAST VALUE 0.0
J 2
(-5625 3400);
DISPLAY 0.617021 (-5625 3400);
PAINT SKYBLUE (-5625 3400);
FORCEPROP 1 LAST PART_NUMBER G21497-005
J 0
(-5700 3450);
DISPLAY 0.617021 (-5700 3450);
PAINT BLUE (-5700 3450);
FORCEPROP 1 LAST LOCATION RT40
J 0
(-5650 3525);
DISPLAY 0.617021 (-5650 3525);
PAINT AQUA (-5650 3525);
FORCEPROP 2 LAST BOM_COST DEBUG
J 0
(-5650 3700);
DISPLAY 1.021277 (-5650 3700);
PAINT ORANGE (-5650 3700);
DISPLAY INVISIBLE (-5650 3700);
FORCEPROP 2 LAST ROOM BMC_DEBUG_HEADER
J 0
(-5650 3650);
DISPLAY 1.021277 (-5650 3650);
PAINT ORANGE (-5650 3650);
DISPLAY INVISIBLE (-5650 3650);
FORCEPROP 1 LAST PATH I72
J 0
(-5650 3650);
DISPLAY 0.978723 (-5650 3650);
PAINT WHITE (-5650 3650);
DISPLAY INVISIBLE (-5650 3650);
FORCEPROP 2 LAST CDS_LIB mstr_discrete
J 0
(-5600 3500);
PAINT MONO (-5600 3500);
DISPLAY INVISIBLE (-5600 3500);
FORCEPROP 1 LASTPIN (-5700 3500) $PN 1
J 0
(-5688 3512);
DISPLAY 0.787234 (-5688 3512);
PAINT ORANGE (-5688 3512);
DISPLAY INVISIBLE (-5688 3512);
FORCEPROP 1 LASTPIN (-5500 3500) $PN 2
J 0
(-5538 3512);
DISPLAY 0.787234 (-5538 3512);
PAINT ORANGE (-5538 3512);
DISPLAY INVISIBLE (-5538 3512);
FORCEADD DNS..2
(-1120 3895);
PAINT RED (-1120 3895);
FORCEPROP 2 LAST CDS_LIB mstr_misc
J 0
(-1120 3895);
PAINT ORANGE (-1120 3895);
DISPLAY INVISIBLE (-1120 3895);
FORCEPROP 1 LAST COMMENT_BODY TRUE
R 1
J 0
(-1045 3670);
DISPLAY 0.872340 (-1045 3670);
PAINT GREEN (-1045 3670);
DISPLAY INVISIBLE (-1045 3670);
FORCEADD DESIGN_NOTE..1
(-1025 1750);
PAINT PURPLE (-1025 1750);
FORCEPROP 0 LAST L1 PVCCSA CPU SPECIFICATIONS:
J 0
(-1220 1625);
PAINT VIOLET (-1220 1625);
FORCEPROP 1 LAST COMMENT_BODY TRUE
J 0
(-1000 1850);
DISPLAY 1.319149 (-1000 1850);
PAINT GREEN (-1000 1850);
DISPLAY INVISIBLE (-1000 1850);
FORCEPROP 2 LAST CDS_LIB mstr_symbols
J 0
(-1025 1750);
PAINT ORANGE (-1025 1750);
DISPLAY INVISIBLE (-1025 1750);
FORCEPROP 2 LAST BOM_COST SM_CONTROLLER
J 0
(-1225 1700);
PAINT MONO (-1225 1700);
DISPLAY INVISIBLE (-1225 1700);
FORCEPROP 2 LAST ROOM PVCCIN_CPU0_VR
J 0
(-1225 1700);
PAINT MONO (-1225 1700);
DISPLAY INVISIBLE (-1225 1700);
FORCEADD INTEL_CORP_BPAGE..1
(0 0);
FORCEPROP 1 LAST CDS_CON_LAST_MODIFIED Tue Dec 01 11:52:22 2015
J 0
(-1425 325);
PAINT ORANGE (-1425 325);
DISPLAY INVISIBLE (-1425 325);
FORCEPROP 1 LAST CUSTOM_TXT_CDS <CURRENT_DESIGN_SHEET> OF <TOTAL_DESIGN_SHEETS>
J 0
(-500 25);
PAINT GREEN (-500 25);
FORCEPROP 1 LAST CUSTOM_TXT_CDS <CON_LAST_MODIFIED>
J 0
(-1925 350);
PAINT GREEN (-1925 350);
FORCEPROP 2 LAST CUSTOM_TXT_CDS <XR_PAGE_TITLE>
J 0
(-7890 5250);
DISPLAY 0.638298 (-7890 5250);
PAINT PINK (-7890 5250);
DISPLAY INVISIBLE (-7890 5250);
FORCEPROP 1 LAST SCH_REV 2.420
J 0
(-250 150);
DISPLAY 0.978723 (-250 150);
PAINT YELLOW (-250 150);
FORCEPROP 1 LAST SCH_DEPT BESD
J 1
(-4450 100);
DISPLAY 1.212766 (-4450 100);
PAINT YELLOW (-4450 100);
FORCEPROP 1 LAST SCH_NUMBER H4694802
J 0
(-1300 150);
DISPLAY 1.212766 (-1300 150);
PAINT YELLOW (-1300 150);
FORCEPROP 1 LAST SCH_ADDRESS3 Santa Clara, CA 95052-8119
J 0
(-3975 25);
DISPLAY 0.617021 (-3975 25);
PAINT GREEN (-3975 25);
FORCEPROP 1 LAST SCH_ADDRESS2 P.O. BOX 58119
J 0
(-3975 75);
DISPLAY 0.617021 (-3975 75);
PAINT GREEN (-3975 75);
FORCEPROP 1 LAST SCH_ADDRESS1 2200 Mission College Blvd.
J 0
(-3975 125);
DISPLAY 0.617021 (-3975 125);
PAINT GREEN (-3975 125);
FORCEPROP 1 LAST SCH_TITLE VSA CPU0
J 0
(-7950 50);
DISPLAY 1.212766 (-7950 50);
PAINT ORANGE (-7950 50);
FORCEPROP 1 LAST COMMENT_BODY TRUE
J 0
(12 12);
DISPLAY 0.468085 (12 12);
PAINT GREEN (12 12);
DISPLAY INVISIBLE (12 12);
FORCEPROP 2 LAST CDS_LIB mstr_symbols
J 0
(0 0);
PAINT MONO (0 0);
DISPLAY INVISIBLE (0 0);
FORCEPROP 2 LAST PAGE_BORDER TRUE
J 0
(-7890 5250);
DISPLAY 0.638298 (-7890 5250);
PAINT PINK (-7890 5250);
DISPLAY INVISIBLE (-7890 5250);
FORCEPROP 2 LAST CDS_XR_PAGE_TITLE CR-205 : @BASEBOARD_FAB2_LIB.BASEBOARD_FAB2(SCH_1):PAGE205
J 0
(-7890 5250);
DISPLAY 0.638298 (-7890 5250);
PAINT PINK (-7890 5250);
DISPLAY INVISIBLE (-7890 5250);
FORCEADD DNS..2
(-5745 1820);
PAINT RED (-5745 1820);
FORCEPROP 2 LAST CDS_LIB mstr_misc
J 0
(-5745 1820);
PAINT ORANGE (-5745 1820);
DISPLAY INVISIBLE (-5745 1820);
FORCEPROP 1 LAST COMMENT_BODY TRUE
R 1
J 0
(-5670 1595);
DISPLAY 0.872340 (-5670 1595);
PAINT GREEN (-5670 1595);
DISPLAY INVISIBLE (-5670 1595);
FORCEADD DESIGN_NOTE..1
(-975 1525);
PAINT PURPLE (-975 1525);
FORCEPROP 2 LAST CDS_LIB mstr_symbols
J 0
(-975 1525);
PAINT ORANGE (-975 1525);
DISPLAY INVISIBLE (-975 1525);
FORCEPROP 1 LAST COMMENT_BODY TRUE
J 0
(-950 1625);
DISPLAY 1.319149 (-950 1625);
PAINT GREEN (-950 1625);
DISPLAY INVISIBLE (-950 1625);
FORCEPROP 2 LAST BOM_COST SM_CONTROLLER
J 0
(-1175 1475);
PAINT MONO (-1175 1475);
DISPLAY INVISIBLE (-1175 1475);
FORCEPROP 2 LAST ROOM PVCCIN_CPU0_VR
J 0
(-1175 1475);
PAINT MONO (-1175 1475);
DISPLAY INVISIBLE (-1175 1475);
WIRE 16 -1 (-2250 1400)(-2250 1500);
WIRE 16 -1 (-2250 1500)(-2000 1500);
WIRE 16 -1 (-2000 1400)(-2000 1500);
WIRE 16 -1 (-2000 1500)(-2000 1625);
WIRE 16 -1 (-2250 1200)(-2250 1075);
WIRE 16 -1 (-2250 1075)(-2000 1075);
WIRE 16 -1 (-2000 1075)(-2000 1200);
WIRE 16 -1 (-2000 950)(-2000 1075);
WIRE 16 -1 (-3000 3325)(-2825 3325);
WIRE 16 -1 (-2825 3275)(-2825 3325);
WIRE 16 -1 (-2825 3225)(-2825 3275);
WIRE 16 -1 (-2825 3275)(-3000 3275);
WIRE 16 -1 (-2825 3175)(-2825 3225);
WIRE 16 -1 (-2825 3225)(-3000 3225);
WIRE 16 -1 (-2825 3125)(-2825 3175);
WIRE 16 -1 (-2825 3175)(-3000 3175);
WIRE 16 -1 (-5000 2425)(-4300 2425);
WIRE 16 -1 (-4300 2425)(-4300 2600);
WIRE 16 -1 (-4250 1100)(-4250 1200);
WIRE 16 -1 (-4250 1200)(-4975 1200);
WIRE 16 -1 (-4125 4225)(-4000 4225);
WIRE 16 -1 (-4125 4225)(-4125 4175);
WIRE 16 -1 (-4125 4175)(-4000 4175);
WIRE 16 -1 (-6600 4175)(-4125 4175);
WIRE 16 -1 (-6600 4100)(-6600 4175);
WIRE 16 -1 (-6600 4175)(-6850 4175);
WIRE 16 -1 (-6850 4050)(-6850 4175);
WIRE 16 -1 (-6850 4175)(-7100 4175);
WIRE 16 -1 (-7100 4075)(-7100 4175);
WIRE 16 -1 (-7100 4175)(-7325 4175);
WIRE 16 -1 (-7325 4050)(-7325 4175);
WIRE 16 -1 (-7325 4175)(-7575 4175);
WIRE 16 -1 (-7575 4100)(-7575 4175);
WIRE 16 -1 (-7575 4425)(-7575 4175);
WIRE 16 -1 (-5775 3900)(-5775 3750);
WIRE 16 -1 (-5775 3750)(-5875 3750);
WIRE 16 -1 (-5875 3900)(-5875 3750);
WIRE 16 -1 (-6350 3750)(-5875 3750);
WIRE 16 -1 (-6350 3850)(-6350 3750);
WIRE 16 -1 (-6350 3750)(-6600 3750);
WIRE 16 -1 (-6600 3900)(-6600 3750);
WIRE 16 -1 (-6600 3750)(-6850 3750);
WIRE 16 -1 (-6850 3850)(-6850 3750);
WIRE 16 -1 (-6850 3750)(-7100 3750);
WIRE 16 -1 (-7100 3875)(-7100 3750);
WIRE 16 -1 (-7100 3750)(-7325 3750);
WIRE 16 -1 (-7325 3850)(-7325 3750);
WIRE 16 -1 (-7325 3750)(-7575 3750);
WIRE 16 -1 (-7575 3900)(-7575 3750);
WIRE 16 -1 (-7575 3600)(-7575 3750);
WIRE 16 -1 (-4000 3875)(-4150 3875);
WIRE 16 -1 (-4150 3875)(-4150 2700);
WIRE 16 -1 (-4150 2700)(-1525 2700);
WIRE 16 -1 (-1525 2700)(-1525 3425);
WIRE 16 -1 (-1625 3425)(-1525 3425);
WIRE 16 -1 (-1300 3425)(-1525 3425);
WIRE 16 -1 (-1300 2975)(-1300 3425);
WIRE 16 -1 (-950 3425)(-1300 3425);
WIRE 16 -1 (-950 2975)(-950 3425);
WIRE 16 -1 (-625 3425)(-950 3425);
WIRE 16 -1 (-625 2975)(-625 3425);
WIRE 16 -1 (-625 3425)(-625 3475);
WIRE 16 -1 (-4000 3975)(-4100 3975);
WIRE 16 -1 (-4100 3975)(-4100 4075);
WIRE 16 -1 (-4100 4075)(-4000 4075);
WIRE 16 -1 (-4900 4075)(-4100 4075);
WIRE 16 -1 (-4900 4525)(-4900 4075);
WIRE 16 -1 (-4900 4525)(-5775 4525);
WIRE 16 -1 (-4900 4600)(-4900 4525);
WIRE 16 -1 (-5775 4525)(-5875 4525);
WIRE 16 -1 (-5775 4100)(-5775 4525);
WIRE 16 -1 (-5875 4100)(-5875 4525);
WIRE 16 -1 (-5875 4525)(-5975 4525);
WIRE 16 -1 (-950 2625)(-1300 2625);
WIRE 16 -1 (-950 2775)(-950 2625);
WIRE 16 -1 (-625 2625)(-950 2625);
WIRE 16 -1 (-1300 2625)(-1300 2775);
WIRE 16 -1 (-625 2775)(-625 2625);
WIRE 16 -1 (-625 2575)(-625 2625);
WIRE 16 -1 (-1125 3800)(-1125 3675);
WIRE 16 -1 (-2375 3650)(-2375 3600);
WIRE 16 -1 (-2225 2825)(-2225 2800);
WIRE 16 -1 (-4200 3125)(-4200 3025);
WIRE 3 2175 (-2375 2725)(-1875 2725);
WIRE 3 2175 (-2375 3475)(-2375 2725);
WIRE 3 2175 (-1875 3475)(-1875 2725);
WIRE 3 2175 (-2375 3475)(-1875 3475);
WIRE 3 2175 (-2525 3975)(-2125 3975);
WIRE 3 2175 (-2525 3975)(-2525 3500);
WIRE 3 2175 (-2125 3975)(-2125 3500);
WIRE 3 2175 (-2525 3500)(-2125 3500);
WIRE 16 -1 (-3000 3425)(-2225 3425);
FORCEPROP 0 LAST VOLTAGE 5
J 0
(-2625 3500);
DISPLAY 1.021277 (-2625 3500);
PAINT SKYBLUE (-2625 3500);
DISPLAY INVISIBLE (-2625 3500);
FORCEPROP 2 LAST SIG_NAME VR_PVSA_CPU0_PHASE_SW
J 0
(-2860 3435);
DISPLAY 0.617021 (-2860 3435);
PAINT ORANGE (-2860 3435);
FORCEPROP 2 LASTPROP $XRERR UNIQUE?
J 0
(-3100 3435);
DISPLAY 0.638298 (-3100 3435);
PAINT MONO (-3100 3435);
DISPLAY INVISIBLE (-3100 3435);
WIRE 16 -1 (-2225 3425)(-1825 3425);
WIRE 16 -1 (-2225 3325)(-2225 3425);
WIRE 3 2175 (-4625 3475)(-3900 3475);
WIRE 3 2175 (-4625 3475)(-4625 2950);
WIRE 3 2175 (-3900 3475)(-3900 2950);
WIRE 3 2175 (-4625 2950)(-3900 2950);
WIRE 16 -1 (-7150 2075)(-6300 2075);
FORCEPROP 2 LAST SIG_NAME VSENSE_PVSA_CPU0_P
J 0
(-7120 2095);
DISPLAY 0.617021 (-7120 2095);
PAINT ORANGE (-7120 2095);
WIRE 16 -1 (-6300 1875)(-6300 2075);
WIRE 16 -1 (-6300 1875)(-5975 1875);
WIRE 16 -1 (-5975 1875)(-5975 2025);
WIRE 16 -1 (-5975 2025)(-5750 2025);
WIRE 16 -1 (-5350 2025)(-5750 2025);
WIRE 16 -1 (-5750 1925)(-5750 2025);
WIRE 16 -1 (-5350 2425)(-5350 2025);
WIRE 16 -1 (-5175 2025)(-5350 2025);
WIRE 16 -1 (-5200 2425)(-5350 2425);
WIRE 16 -1 (-6400 3225)(-4525 3225);
FORCEPROP 0 LAST VOLTAGE 5
J 0
(-6300 3300);
DISPLAY 1.021277 (-6300 3300);
PAINT SKYBLUE (-6300 3300);
DISPLAY INVISIBLE (-6300 3300);
FORCEPROP 2 LAST SIG_NAME VR_PVSA_CPU0_PHASE
J 0
(-6309 3235);
DISPLAY 0.617021 (-6309 3235);
PAINT ORANGE (-6309 3235);
FORCEPROP 2 LASTPROP $XRERR UNIQUE?
J 0
(-6549 3235);
DISPLAY 0.638298 (-6549 3235);
PAINT MONO (-6549 3235);
DISPLAY INVISIBLE (-6549 3235);
WIRE 16 -1 (-6400 3225)(-6400 3250);
WIRE 16 -1 (-4525 3225)(-4525 3375);
WIRE 16 -1 (-4525 3375)(-4000 3375);
WIRE 16 -1 (-5500 3500)(-4525 3500);
FORCEPROP 2 LAST SIG_NAME VR_PVSA_CPU0_BOOT_R
J 0
(-5259 3510);
DISPLAY 0.617021 (-5259 3510);
PAINT ORANGE (-5259 3510);
FORCEPROP 2 LASTPROP $XRERR UNIQUE?
J 0
(-5499 3510);
DISPLAY 0.638298 (-5499 3510);
PAINT MONO (-5499 3510);
DISPLAY INVISIBLE (-5499 3510);
WIRE 16 -1 (-4525 3500)(-4525 3425);
WIRE 16 -1 (-4525 3425)(-4000 3425);
WIRE 3 2175 (-5875 3575)(-5350 3575);
WIRE 3 2175 (-5875 3575)(-5875 3300);
WIRE 3 2175 (-5350 3575)(-5350 3300);
WIRE 3 2175 (-5875 3300)(-5350 3300);
WIRE 16 -1 (-5700 3500)(-6400 3500);
FORCEPROP 2 LAST SIG_NAME VR_PVSA_CPU0_BOOT
J 0
(-6359 3510);
DISPLAY 0.617021 (-6359 3510);
PAINT ORANGE (-6359 3510);
FORCEPROP 2 LASTPROP $XRERR UNIQUE?
J 0
(-6599 3510);
DISPLAY 0.638298 (-6599 3510);
PAINT MONO (-6599 3510);
DISPLAY INVISIBLE (-6599 3510);
WIRE 16 -1 (-6400 3500)(-6400 3450);
WIRE 16 2175 (-6750 3550)(-5925 3550);
WIRE 16 2175 (-6750 3550)(-6750 3150);
WIRE 16 2175 (-5925 3550)(-5925 3150);
WIRE 16 2175 (-6750 3150)(-5925 3150);
WIRE 16 682 (-350 1600)(-350 875);
WIRE 16 682 (-1200 1600)(-350 1600);
WIRE 16 682 (-350 875)(-1200 875);
WIRE 16 682 (-1200 875)(-1200 1600);
WIRE 16 682 (-6125 4150)(-5525 4150);
WIRE 16 682 (-6125 3775)(-6125 4150);
WIRE 16 682 (-5525 4150)(-5525 3775);
WIRE 16 682 (-6125 3775)(-5525 3775);
WIRE 16 -1 (-4975 2025)(-3800 2025);
FORCEPROP 2 LAST SIG_NAME VSENSE_PVSA_CPU0_SKT_VSEN
J 0
(-4745 2045);
DISPLAY 0.617021 (-4745 2045);
PAINT ORANGE (-4745 2045);
WIRE 16 -1 (-4000 4275)(-6350 4275);
FORCEPROP 0 LAST VOLTAGE 5
J 0
(-5725 4350);
DISPLAY 1.021277 (-5725 4350);
PAINT SKYBLUE (-5725 4350);
DISPLAY INVISIBLE (-5725 4350);
FORCEPROP 2 LAST SIG_NAME VR_PVSA_CPU0_VCIN
J 0
(-6309 4285);
DISPLAY 0.617021 (-6309 4285);
PAINT ORANGE (-6309 4285);
FORCEPROP 2 LASTPROP $XRERR UNIQUE?
J 0
(-6549 4285);
DISPLAY 0.638298 (-6549 4285);
PAINT MONO (-6549 4285);
DISPLAY INVISIBLE (-6549 4285);
WIRE 16 -1 (-6350 4275)(-6350 4525);
WIRE 16 -1 (-6350 4050)(-6350 4275);
WIRE 16 -1 (-6350 4525)(-6175 4525);
WIRE 16 -1 (-3000 3925)(-2375 3925);
FORCEPROP 2 LAST SIG_NAME A_TSENSE_PVSA_CPU0
J 0
(-3004 3935);
DISPLAY 0.617021 (-3004 3935);
PAINT ORANGE (-3004 3935);
WIRE 16 -1 (-3000 3925)(-3000 3775);
WIRE 16 -1 (-2375 3925)(-1925 3925);
WIRE 16 -1 (-2375 3850)(-2375 3925);
WIRE 16 -1 (-2225 3075)(-2225 3175);
WIRE 16 -1 (-6750 3625)(-4000 3625);
FORCEPROP 2 LAST SIG_NAME VR_PVSA_CPU0_PWM
J 0
(-6683 3635);
DISPLAY 0.617021 (-6683 3635);
PAINT ORANGE (-6683 3635);
WIRE 16 -1 (-3000 4275)(-1750 4275);
FORCEPROP 2 LAST SIG_NAME ISENSE_PVSA_CPU0_IMON
J 0
(-2586 4287);
DISPLAY 0.617021 (-2586 4287);
PAINT ORANGE (-2586 4287);
WIRE 16 -1 (-3000 4075)(-1125 4075);
FORCEPROP 0 LAST SIG_NAME VR_PVSA_CPU0_OCSET
J 0
(-2860 4085);
DISPLAY 0.617021 (-2860 4085);
PAINT ORANGE (-2860 4085);
FORCEPROP 2 LASTPROP $XRERR UNIQUE?
J 0
(-3100 4085);
DISPLAY 0.638298 (-3100 4085);
PAINT MONO (-3100 4085);
DISPLAY INVISIBLE (-3100 4085);
WIRE 16 -1 (-1125 4075)(-1125 4000);
WIRE 16 -1 (-4000 3525)(-4200 3525);
WIRE 16 -1 (-4200 3525)(-4200 4675);
WIRE 16 -1 (-4200 3325)(-4200 3525);
WIRE 16 -1 (-4200 4675)(-1675 4675);
FORCEPROP 2 LAST SIG_NAME VR_PVSA_CPU0_BIREF1
J 0
(-2889 4700);
DISPLAY 0.617021 (-2889 4700);
PAINT ORANGE (-2889 4700);
WIRE 16 -1 (-4975 1575)(-3800 1575);
FORCEPROP 2 LAST SIG_NAME VSENSE_PVSA_CPU0_SKT_VRTN
J 0
(-4745 1595);
DISPLAY 0.617021 (-4745 1595);
PAINT ORANGE (-4745 1595);
WIRE 16 -1 (-7175 1600)(-6300 1600);
FORCEPROP 2 LAST SIG_NAME VSENSE_PVSA_CPU0_N
J 0
(-7170 1620);
DISPLAY 0.617021 (-7170 1620);
PAINT ORANGE (-7170 1620);
WIRE 16 -1 (-6300 1600)(-6300 1800);
WIRE 16 -1 (-6300 1800)(-5975 1800);
WIRE 16 -1 (-5975 1800)(-5975 1575);
WIRE 16 -1 (-5975 1575)(-5750 1575);
WIRE 16 -1 (-5325 1575)(-5750 1575);
WIRE 16 -1 (-5750 1725)(-5750 1575);
WIRE 16 -1 (-5175 1575)(-5325 1575);
WIRE 16 -1 (-5325 1200)(-5325 1575);
WIRE 16 -1 (-5175 1200)(-5325 1200);
WIRE 16 -1 (-3000 4025)(-2425 4025);
FORCEPROP 2 LAST SIG_NAME NC_PVSA_CPU0_P31
J 0
(-2859 4035);
DISPLAY 0.617021 (-2859 4035);
PAINT ORANGE (-2859 4035);
FORCEPROP 2 LASTPROP $XRERR UNIQUE?
J 0
(-2395 4025);
DISPLAY 0.638298 (-2395 4025);
PAINT MONO (-2395 4025);
DISPLAY INVISIBLE (-2395 4025);
WIRE 16 -1 (-4000 3775)(-4775 3775);
FORCEPROP 0 LAST SIG_NAME TP_PVSA_CPU0_GL_1
J 0
(-4760 3785);
DISPLAY 0.617021 (-4760 3785);
PAINT ORANGE (-4760 3785);
FORCEPROP 2 LASTPROP $XRERR UNIQUE?
J 0
(-5015 3775);
DISPLAY 0.638298 (-5015 3775);
PAINT MONO (-5015 3775);
DISPLAY INVISIBLE (-5015 3775);
WIRE 16 -1 (-4000 3725)(-4775 3725);
FORCEPROP 0 LAST SIG_NAME TP_PVSA_CPU0_GL_0
J 0
(-4760 3735);
DISPLAY 0.617021 (-4760 3735);
PAINT ORANGE (-4760 3735);
FORCEPROP 2 LASTPROP $XRERR UNIQUE?
J 0
(-5015 3725);
DISPLAY 0.638298 (-5015 3725);
PAINT MONO (-5015 3725);
DISPLAY INVISIBLE (-5015 3725);
DOT 1 (-625 3425);
DOT 1 (-950 3425);
DOT 1 (-625 2625);
DOT 1 (-950 2625);
DOT 1 (-1300 3425);
DOT 1 (-2000 1500);
DOT 1 (-2000 1075);
DOT 1 (-2825 3225);
DOT 1 (-4125 4175);
DOT 1 (-4900 4525);
DOT 1 (-5775 4525);
DOT 1 (-6850 4175);
DOT 1 (-7325 4175);
DOT 1 (-7575 4175);
DOT 1 (-4100 4075);
DOT 1 (-5875 3750);
DOT 1 (-5325 1575);
DOT 1 (-5750 2025);
DOT 1 (-5750 1575);
DOT 1 (-6350 3750);
DOT 1 (-6600 3750);
DOT 1 (-6850 3750);
DOT 1 (-7100 3750);
DOT 1 (-7325 3750);
DOT 1 (-7575 3750);
DOT 1 (-2225 3425);
DOT 1 (-4200 3525);
DOT 1 (-6600 4175);
DOT 1 (-2825 3175);
DOT 1 (-5350 2025);
DOT 1 (-2825 3275);
DOT 1 (-2375 3925);
DOT 1 (-6350 4275);
DOT 1 (-5875 4525);
DOT 1 (-1525 3425);
DOT 1 (-7100 4175);
FORCENOTE
IOUT PK=13A
(-1175 1125) 0;
DISPLAY LEFT (-1175 1125);
DISPLAY 0.808511 (-1175 1125);
PAINT PURPLE (-1175 1125);
FORCENOTE
IOUT TDC=12A
(-1175 1175) 0;
DISPLAY LEFT (-1175 1175);
DISPLAY 0.808511 (-1175 1175);
PAINT PURPLE (-1175 1175);
FORCENOTE
DC TOL = +/-5MV
(-1175 1275) 0;
DISPLAY LEFT (-1175 1275);
DISPLAY 0.808511 (-1175 1275);
PAINT PURPLE (-1175 1275);
FORCENOTE
ROOM = PVSA_CPU0_DECAP_VR
(-3265 665) 0;
DISPLAY LEFT (-3265 665);
DISPLAY 2.446809 (-3265 665);
PAINT PURPLE (-3265 665);
FORCENOTE
SOCKET SIDE
(-4265 1840) 0;
DISPLAY LEFT (-4265 1840);
PAINT PURPLE (-4265 1840);
FORCENOTE
ROUT AS DIFF PAIR
(-6365 1815) 0;
DISPLAY LEFT (-6365 1815);
DISPLAY 0.808511 (-6365 1815);
PAINT PURPLE (-6365 1815);
FORCENOTE
10MIL WIDTH
(-6240 1740) 0;
DISPLAY LEFT (-6240 1740);
DISPLAY 0.808511 (-6240 1740);
PAINT PURPLE (-6240 1740);
FORCENOTE
5MIL SPACING
(-6265 1665) 0;
DISPLAY LEFT (-6265 1665);
DISPLAY 0.808511 (-6265 1665);
PAINT PURPLE (-6265 1665);
FORCENOTE
VR CONTROLLER SIDE
(-7390 1840) 0;
DISPLAY LEFT (-7390 1840);
PAINT PURPLE (-7390 1840);
FORCENOTE
PVSA CPU0 VOLTAGE SENSE
(-6990 1465) 0;
DISPLAY LEFT (-6990 1465);
PAINT PURPLE (-6990 1465);
FORCENOTE
SPOF
(-6680 3050) 0;
DISPLAY LEFT (-6680 3050);
DISPLAY 1.808511 (-6680 3050);
PAINT PURPLE (-6680 3050);
FORCENOTE
ROOM = PVSA_CPU0_VSENSE_VR
(-6865 815) 0;
DISPLAY LEFT (-6865 815);
DISPLAY 2.446809 (-6865 815);
PAINT PURPLE (-6865 815);
FORCENOTE
PLACE ON TOP
(-6105 3675) 0;
DISPLAY LEFT (-6105 3675);
DISPLAY 1.553191 (-6105 3675);
PAINT PURPLE (-6105 3675);
FORCENOTE
RIPPLE = +/- 10MV
(-1175 1325) 0;
DISPLAY LEFT (-1175 1325);
DISPLAY 0.808511 (-1175 1325);
PAINT PURPLE (-1175 1325);
FORCENOTE
VOUT=0.85V (TYP) SVID
(-1175 1375) 0;
DISPLAY LEFT (-1175 1375);
DISPLAY 0.808511 (-1175 1375);
PAINT PURPLE (-1175 1375);
FORCENOTE
TOTAL TOL = 0.917MAX/0.779VMIN 
(-1175 1225) 0;
DISPLAY LEFT (-1175 1225);
DISPLAY 0.808511 (-1175 1225);
PAINT PURPLE (-1175 1225);
FORCENOTE
IOUT STEP=5A/US
(-1175 1075) 0;
DISPLAY LEFT (-1175 1075);
DISPLAY 0.808511 (-1175 1075);
PAINT PURPLE (-1175 1075);
FORCENOTE
IOUT DI/DT =20A/US
(-1175 1025) 0;
DISPLAY LEFT (-1175 1025);
DISPLAY 0.808511 (-1175 1025);
PAINT PURPLE (-1175 1025);
FORCENOTE
SW FREQ=520 KHZ
(-1175 975) 0;
DISPLAY LEFT (-1175 975);
DISPLAY 0.808511 (-1175 975);
PAINT PURPLE (-1175 975);
FORCENOTE
VBOOT=0.9V
(-1175 925) 0;
DISPLAY LEFT (-1175 925);
DISPLAY 0.808511 (-1175 925);
PAINT PURPLE (-1175 925);
FORCENOTE
TP FAB1 CO-LAY WITH TI PARTS 11/16
(-5625 3100) 0;
DISPLAY LEFT (-5625 3100);
DISPLAY 0.851064 (-5625 3100);
PAINT RED (-5625 3100);
FORCENOTE
TP FAB1 3.01 OHM NEED CHANGE TO 2.2 OHM BUT WAIT FOR SYMBOL
(-2925 2500) 0;
DISPLAY LEFT (-2925 2500);
DISPLAY 0.851064 (-2925 2500);
PAINT RED (-2925 2500);
FORCENOTE
TP FAB1 CO-LAY WITH TI PARTS 11/16
(-2925 2575) 0;
DISPLAY LEFT (-2925 2575);
DISPLAY 0.851064 (-2925 2575);
PAINT RED (-2925 2575);
FORCENOTE
TP FAB1 CO-LAY WITH TI PARTS 11/16
(-2075 3700) 0;
DISPLAY LEFT (-2075 3700);
DISPLAY 0.851064 (-2075 3700);
PAINT RED (-2075 3700);
FORCENOTE
ROOM=PVSA_CPU0_PWR_VR
(-3180 1860) 0;
DISPLAY LEFT (-3180 1860);
DISPLAY 2.446809 (-3180 1860);
PAINT PURPLE (-3180 1860);
QUIT
